FILE_TYPE = MACRO_DRAWING;
SET COLOR_WIRE YELLOW;
SET COLOR_PROP MONO;
SET COLOR_DOT WHITE;
SET COLOR_ARC YELLOW;
SET COLOR_BODY GREEN;
SET COLOR_NOTE MONO;
SET PROP_DISPLAY VALUE;
SET PAGE_NUMBER P190;
FORCEADD RES..1
(-4150 5200);
FORCEPROP 1 LASTPIN (-4050 5200) $PN 2
J 0
(-4088 5212);
DISPLAY 0.617021 (-4088 5212);
PAINT ORANGE (-4088 5212);
FORCEPROP 1 LAST LOCATION R3P34
J 0
(-4375 5225);
DISPLAY 0.617021 (-4375 5225);
PAINT AQUA (-4375 5225);
FORCEPROP 1 LASTPIN (-4250 5200) $PN 1
J 0
(-4238 5212);
DISPLAY 0.617021 (-4238 5212);
PAINT ORANGE (-4238 5212);
FORCEPROP 1 LAST PART_NUMBER G21497-005
J 0
(-4300 5150);
DISPLAY 0.617021 (-4300 5150);
PAINT BLUE (-4300 5150);
FORCEPROP 1 LAST VALUE 0.0
J 2
(-4250 5100);
DISPLAY 0.617021 (-4250 5100);
PAINT SKYBLUE (-4250 5100);
FORCEPROP 1 LAST TOLERANCE 5%
J 0
(-4200 5100);
DISPLAY 0.617021 (-4200 5100);
PAINT SKYBLUE (-4200 5100);
FORCEPROP 1 LAST PACK_TYPE 0402
J 0
(-4075 5100);
DISPLAY 0.617021 (-4075 5100);
PAINT SKYBLUE (-4075 5100);
FORCEPROP 1 LAST MATERIAL CHIP
J 0
(-4150 5050);
DISPLAY 0.617021 (-4150 5050);
PAINT SKYBLUE (-4150 5050);
FORCEPROP 1 LAST WATTAGE 1/16W
J 2
(-4175 5050);
DISPLAY 0.617021 (-4175 5050);
PAINT SKYBLUE (-4175 5050);
FORCEPROP 2 LAST SEC_TYPE 0402
J 0
(-4200 5400);
DISPLAY 1.021277 (-4200 5400);
PAINT ORANGE (-4200 5400);
DISPLAY INVISIBLE (-4200 5400);
FORCEPROP 2 LAST CDS_LIB mstr_discrete
J 0
(-4150 5200);
PAINT ORANGE (-4150 5200);
DISPLAY INVISIBLE (-4150 5200);
FORCEPROP 0 LAST BOM_COST CPLD
J 0
(-4375 5325);
DISPLAY 1.021277 (-4375 5325);
PAINT ORANGE (-4375 5325);
DISPLAY INVISIBLE (-4375 5325);
FORCEPROP 2 LAST SEC 1
J 0
(-4200 5400);
DISPLAY 0.680851 (-4200 5400);
PAINT MONO (-4200 5400);
DISPLAY INVISIBLE (-4200 5400);
FORCEPROP 2 LAST CDS_LOCATION R3P34
J 0
(-4375 5225);
DISPLAY 0.617021 (-4375 5225);
PAINT AQUA (-4375 5225);
DISPLAY INVISIBLE (-4375 5225);
FORCEPROP 1 LAST PATH I116
J 0
(-4200 5350);
DISPLAY 0.978723 (-4200 5350);
PAINT WHITE (-4200 5350);
DISPLAY INVISIBLE (-4200 5350);
FORCEPROP 2 LAST ROOM CPLD
J 0
(-4200 5300);
DISPLAY 1.361702 (-4200 5300);
PAINT ORANGE (-4200 5300);
DISPLAY INVISIBLE (-4200 5300);
FORCEADD RES..1
(-4150 5000);
FORCEPROP 1 LASTPIN (-4050 5000) $PN 2
J 0
(-4088 5012);
DISPLAY 0.617021 (-4088 5012);
PAINT ORANGE (-4088 5012);
FORCEPROP 1 LAST WATTAGE 1/16W
J 2
(-4400 4900);
DISPLAY 0.617021 (-4400 4900);
PAINT SKYBLUE (-4400 4900);
FORCEPROP 1 LASTPIN (-4250 5000) $PN 1
J 0
(-4238 5012);
DISPLAY 0.617021 (-4238 5012);
PAINT ORANGE (-4238 5012);
FORCEPROP 1 LAST LOCATION R3P35
J 0
(-4375 5000);
DISPLAY 0.617021 (-4375 5000);
PAINT AQUA (-4375 5000);
FORCEPROP 1 LAST PART_NUMBER G21497-005
J 0
(-4300 4950);
DISPLAY 0.617021 (-4300 4950);
PAINT BLUE (-4300 4950);
FORCEPROP 1 LAST TOLERANCE 5%
J 0
(-4200 4900);
DISPLAY 0.617021 (-4200 4900);
PAINT SKYBLUE (-4200 4900);
FORCEPROP 1 LAST PACK_TYPE 0402
J 0
(-4075 4900);
DISPLAY 0.617021 (-4075 4900);
PAINT SKYBLUE (-4075 4900);
FORCEPROP 1 LAST MATERIAL CHIP
J 0
(-3950 4900);
DISPLAY 0.617021 (-3950 4900);
PAINT SKYBLUE (-3950 4900);
FORCEPROP 1 LAST VALUE 0.0
J 2
(-4250 4900);
DISPLAY 0.617021 (-4250 4900);
PAINT SKYBLUE (-4250 4900);
FORCEPROP 2 LAST SEC_TYPE 0402
J 0
(-4200 5200);
DISPLAY 1.021277 (-4200 5200);
PAINT ORANGE (-4200 5200);
DISPLAY INVISIBLE (-4200 5200);
FORCEPROP 0 LAST BOM_COST CPLD
J 0
(-4375 5100);
DISPLAY 1.021277 (-4375 5100);
PAINT ORANGE (-4375 5100);
DISPLAY INVISIBLE (-4375 5100);
FORCEPROP 2 LAST CDS_LIB mstr_discrete
J 0
(-4150 5000);
PAINT ORANGE (-4150 5000);
DISPLAY INVISIBLE (-4150 5000);
FORCEPROP 2 LAST SEC 1
J 0
(-4200 5200);
DISPLAY 0.680851 (-4200 5200);
PAINT MONO (-4200 5200);
DISPLAY INVISIBLE (-4200 5200);
FORCEPROP 2 LAST CDS_LOCATION R3P35
J 0
(-4375 5000);
DISPLAY 0.617021 (-4375 5000);
PAINT AQUA (-4375 5000);
DISPLAY INVISIBLE (-4375 5000);
FORCEPROP 1 LAST PATH I117
J 0
(-4200 5150);
DISPLAY 0.978723 (-4200 5150);
PAINT WHITE (-4200 5150);
DISPLAY INVISIBLE (-4200 5150);
FORCEPROP 2 LAST ROOM CPLD
J 0
(-4200 5100);
DISPLAY 1.361702 (-4200 5100);
PAINT ORANGE (-4200 5100);
DISPLAY INVISIBLE (-4200 5100);
FORCEADD OFFPAGE..1
(-4925 5000);
FORCEPROP 2 LAST $XR0 190 
J 0
(-5177 5000);
DISPLAY 0.638298 (-5177 5000);
PAINT MONO (-5177 5000);
FORCEPROP 2 LAST PATH I118
J 0
(-4875 5075);
DISPLAY 1.021277 (-4875 5075);
PAINT ORANGE (-4875 5075);
DISPLAY INVISIBLE (-4875 5075);
FORCEPROP 2 LAST CDS_LIB mstr_standard
J 0
(-4925 5000);
PAINT ORANGE (-4925 5000);
DISPLAY INVISIBLE (-4925 5000);
FORCEPROP 2 LAST BOM_COST SB_RESET
J 0
(-5175 5050);
DISPLAY 1.617021 (-5175 5050);
PAINT WHITE (-5175 5050);
DISPLAY INVISIBLE (-5175 5050);
FORCEPROP 2 LAST ROOM PLD
J 0
(-5175 5050);
DISPLAY 1.617021 (-5175 5050);
PAINT WHITE (-5175 5050);
DISPLAY INVISIBLE (-5175 5050);
FORCEPROP 1 LAST OFFPAGE TRUE
J 0
(-4600 4875);
PAINT GREEN (-4600 4875);
DISPLAY INVISIBLE (-4600 4875);
FORCEPROP 1 LAST COMMENT_BODY TRUE
J 0
(-4800 4900);
DISPLAY 1.893617 (-4800 4900);
PAINT PEACH (-4800 4900);
DISPLAY INVISIBLE (-4800 4900);
FORCEADD OFFPAGE..1
(-4925 5200);
FORCEPROP 2 LAST $XR0 190 
J 0
(-5177 5200);
DISPLAY 0.638298 (-5177 5200);
PAINT MONO (-5177 5200);
FORCEPROP 2 LAST PATH I119
J 0
(-4875 5275);
DISPLAY 1.021277 (-4875 5275);
PAINT ORANGE (-4875 5275);
DISPLAY INVISIBLE (-4875 5275);
FORCEPROP 2 LAST CDS_LIB mstr_standard
J 0
(-4925 5200);
PAINT ORANGE (-4925 5200);
DISPLAY INVISIBLE (-4925 5200);
FORCEPROP 2 LAST ROOM PLD
J 0
(-5175 5250);
DISPLAY 1.617021 (-5175 5250);
PAINT WHITE (-5175 5250);
DISPLAY INVISIBLE (-5175 5250);
FORCEPROP 2 LAST BOM_COST SB_RESET
J 0
(-5175 5250);
DISPLAY 1.617021 (-5175 5250);
PAINT WHITE (-5175 5250);
DISPLAY INVISIBLE (-5175 5250);
FORCEPROP 1 LAST OFFPAGE TRUE
J 0
(-4600 5075);
PAINT GREEN (-4600 5075);
DISPLAY INVISIBLE (-4600 5075);
FORCEPROP 1 LAST COMMENT_BODY TRUE
J 0
(-4800 5100);
DISPLAY 1.893617 (-4800 5100);
PAINT PEACH (-4800 5100);
DISPLAY INVISIBLE (-4800 5100);
FORCEADD OFFPAGE..2
(-3175 5200);
FORCEPROP 2 LAST $XR0 96 
J 0
(-2986 5200);
DISPLAY 0.638298 (-2986 5200);
PAINT MONO (-2986 5200);
FORCEPROP 2 LAST PATH I120
J 0
(-3125 5275);
DISPLAY 1.021277 (-3125 5275);
PAINT ORANGE (-3125 5275);
DISPLAY INVISIBLE (-3125 5275);
FORCEPROP 2 LAST BOM_COST SB_RESET
J 0
(-3425 5250);
DISPLAY 1.617021 (-3425 5250);
PAINT WHITE (-3425 5250);
DISPLAY INVISIBLE (-3425 5250);
FORCEPROP 2 LAST ROOM PLD
J 0
(-3425 5250);
DISPLAY 1.617021 (-3425 5250);
PAINT WHITE (-3425 5250);
DISPLAY INVISIBLE (-3425 5250);
FORCEPROP 2 LAST CDS_LIB mstr_standard
J 0
(-3175 5200);
PAINT ORANGE (-3175 5200);
DISPLAY INVISIBLE (-3175 5200);
FORCEPROP 1 LAST OFFPAGE TRUE
J 0
(-2850 5075);
DISPLAY 0.872340 (-2850 5075);
PAINT GREEN (-2850 5075);
DISPLAY INVISIBLE (-2850 5075);
FORCEPROP 1 LAST COMMENT_BODY TRUE
J 0
(-3220 5105);
DISPLAY 0.872340 (-3220 5105);
PAINT GREEN (-3220 5105);
DISPLAY INVISIBLE (-3220 5105);
FORCEADD OFFPAGE..2
(-3175 5000);
FORCEPROP 2 LAST $XR0 96 
J 0
(-2986 5000);
DISPLAY 0.638298 (-2986 5000);
PAINT MONO (-2986 5000);
FORCEPROP 2 LAST PATH I121
J 0
(-3000 5075);
DISPLAY 1.021277 (-3000 5075);
PAINT ORANGE (-3000 5075);
DISPLAY INVISIBLE (-3000 5075);
FORCEPROP 2 LAST ROOM PLD
J 0
(-3425 5050);
DISPLAY 1.617021 (-3425 5050);
PAINT WHITE (-3425 5050);
DISPLAY INVISIBLE (-3425 5050);
FORCEPROP 2 LAST BOM_COST SB_RESET
J 0
(-3425 5050);
DISPLAY 1.617021 (-3425 5050);
PAINT WHITE (-3425 5050);
DISPLAY INVISIBLE (-3425 5050);
FORCEPROP 2 LAST CDS_LIB mstr_standard
J 0
(-3175 5000);
PAINT ORANGE (-3175 5000);
DISPLAY INVISIBLE (-3175 5000);
FORCEPROP 1 LAST OFFPAGE TRUE
J 0
(-2850 4875);
DISPLAY 0.872340 (-2850 4875);
PAINT GREEN (-2850 4875);
DISPLAY INVISIBLE (-2850 4875);
FORCEPROP 1 LAST COMMENT_BODY TRUE
J 0
(-3220 4905);
DISPLAY 0.872340 (-3220 4905);
PAINT GREEN (-3220 4905);
DISPLAY INVISIBLE (-3220 4905);
FORCEADD OFFPAGE..4
(300 4500);
FORCEPROP 2 LAST $XR0 119 
J 0
(486 4500);
DISPLAY 0.638298 (486 4500);
PAINT MONO (486 4500);
FORCEPROP 2 LAST CDS_LIB mstr_standard
J 0
(300 4500);
PAINT ORANGE (300 4500);
DISPLAY INVISIBLE (300 4500);
FORCEPROP 2 LAST PATH I122
J 0
(500 4550);
DISPLAY 1.021277 (500 4550);
PAINT ORANGE (500 4550);
DISPLAY INVISIBLE (500 4550);
FORCEPROP 1 LAST OFFPAGE TRUE
J 0
(625 4375);
DISPLAY 1.170213 (625 4375);
PAINT GREEN (625 4375);
DISPLAY INVISIBLE (625 4375);
FORCEPROP 1 LAST COMMENT_BODY TRUE
J 0
(275 4400);
DISPLAY 1.170213 (275 4400);
PAINT GREEN (275 4400);
DISPLAY INVISIBLE (275 4400);
FORCEADD OFFPAGE..2
(300 4100);
FORCEPROP 2 LAST $XR0 248 
J 0
(489 4100);
DISPLAY 0.638298 (489 4100);
PAINT MONO (489 4100);
FORCEPROP 2 LAST CDS_LIB mstr_standard
J 0
(300 4100);
PAINT ORANGE (300 4100);
DISPLAY INVISIBLE (300 4100);
FORCEPROP 2 LAST PATH I134
J 0
(500 4150);
DISPLAY 1.021277 (500 4150);
PAINT ORANGE (500 4150);
DISPLAY INVISIBLE (500 4150);
FORCEPROP 1 LAST OFFPAGE TRUE
J 0
(625 3975);
DISPLAY 1.170213 (625 3975);
PAINT GREEN (625 3975);
DISPLAY INVISIBLE (625 3975);
FORCEPROP 1 LAST COMMENT_BODY TRUE
J 0
(255 4005);
DISPLAY 1.170213 (255 4005);
PAINT GREEN (255 4005);
DISPLAY INVISIBLE (255 4005);
FORCEADD OFFPAGE..4
(300 3650);
FORCEPROP 2 LAST $XR1 230 
J 0
(606 3650);
DISPLAY 0.638298 (606 3650);
PAINT MONO (606 3650);
FORCEPROP 2 LAST $XR0 229 
J 0
(486 3650);
DISPLAY 0.638298 (486 3650);
PAINT MONO (486 3650);
FORCEPROP 2 LAST CDS_LIB mstr_standard
J 2
(300 3650);
PAINT ORANGE (300 3650);
DISPLAY INVISIBLE (300 3650);
FORCEPROP 2 LAST PATH I139
J 0
(800 3700);
DISPLAY 1.021277 (800 3700);
PAINT ORANGE (800 3700);
DISPLAY INVISIBLE (800 3700);
FORCEPROP 1 LAST OFFPAGE TRUE
J 0
(625 3525);
DISPLAY 1.170213 (625 3525);
PAINT GREEN (625 3525);
DISPLAY INVISIBLE (625 3525);
FORCEPROP 1 LAST COMMENT_BODY TRUE
J 0
(275 3550);
DISPLAY 1.170213 (275 3550);
PAINT GREEN (275 3550);
DISPLAY INVISIBLE (275 3550);
FORCEADD OFFPAGE..4
(300 3150);
FORCEPROP 2 LAST $XR0 235 
J 0
(486 3150);
DISPLAY 0.638298 (486 3150);
PAINT MONO (486 3150);
FORCEPROP 2 LAST CDS_LIB mstr_standard
J 2
(300 3150);
PAINT ORANGE (300 3150);
DISPLAY INVISIBLE (300 3150);
FORCEPROP 2 LAST PATH I146
J 0
(1100 3200);
DISPLAY 1.021277 (1100 3200);
PAINT ORANGE (1100 3200);
DISPLAY INVISIBLE (1100 3200);
FORCEPROP 1 LAST OFFPAGE TRUE
J 0
(625 3025);
DISPLAY 1.170213 (625 3025);
PAINT GREEN (625 3025);
DISPLAY INVISIBLE (625 3025);
FORCEPROP 1 LAST COMMENT_BODY TRUE
J 0
(275 3050);
DISPLAY 1.170213 (275 3050);
PAINT GREEN (275 3050);
DISPLAY INVISIBLE (275 3050);
FORCEADD OFFPAGE..2
(300 2350);
FORCEPROP 2 LAST $XR1 63 
J 0
(609 2350);
DISPLAY 0.638298 (609 2350);
PAINT MONO (609 2350);
FORCEPROP 2 LAST $XR0 192 
J 0
(489 2350);
DISPLAY 0.638298 (489 2350);
PAINT MONO (489 2350);
FORCEPROP 2 LAST CDS_LIB mstr_standard
J 0
(300 2350);
PAINT ORANGE (300 2350);
DISPLAY INVISIBLE (300 2350);
FORCEPROP 2 LAST PATH I157
J 0
(500 2400);
DISPLAY 1.021277 (500 2400);
PAINT ORANGE (500 2400);
DISPLAY INVISIBLE (500 2400);
FORCEPROP 1 LAST OFFPAGE TRUE
J 0
(625 2225);
DISPLAY 1.170213 (625 2225);
PAINT GREEN (625 2225);
DISPLAY INVISIBLE (625 2225);
FORCEPROP 1 LAST COMMENT_BODY TRUE
J 0
(255 2255);
DISPLAY 1.170213 (255 2255);
PAINT GREEN (255 2255);
DISPLAY INVISIBLE (255 2255);
FORCEADD OFFPAGE..2
(300 2250);
FORCEPROP 2 LAST $XR0 190 
J 0
(489 2250);
DISPLAY 0.638298 (489 2250);
PAINT MONO (489 2250);
FORCEPROP 2 LAST CDS_LIB mstr_standard
J 0
(300 2250);
PAINT ORANGE (300 2250);
DISPLAY INVISIBLE (300 2250);
FORCEPROP 2 LAST PATH I159
J 0
(500 2300);
DISPLAY 1.021277 (500 2300);
PAINT ORANGE (500 2300);
DISPLAY INVISIBLE (500 2300);
FORCEPROP 1 LAST OFFPAGE TRUE
J 0
(625 2125);
DISPLAY 1.170213 (625 2125);
PAINT GREEN (625 2125);
DISPLAY INVISIBLE (625 2125);
FORCEPROP 1 LAST COMMENT_BODY TRUE
J 0
(255 2155);
DISPLAY 1.170213 (255 2155);
PAINT GREEN (255 2155);
DISPLAY INVISIBLE (255 2155);
FORCEADD OFFPAGE..4
(300 2100);
FORCEPROP 2 LAST $XR0 55 
J 0
(486 2100);
DISPLAY 0.638298 (486 2100);
PAINT MONO (486 2100);
FORCEPROP 2 LAST CDS_LIB mstr_standard
J 0
(300 2100);
PAINT ORANGE (300 2100);
DISPLAY INVISIBLE (300 2100);
FORCEPROP 2 LAST PATH I161
J 0
(500 2150);
DISPLAY 1.021277 (500 2150);
PAINT ORANGE (500 2150);
DISPLAY INVISIBLE (500 2150);
FORCEPROP 1 LAST OFFPAGE TRUE
J 0
(625 1975);
DISPLAY 1.170213 (625 1975);
PAINT GREEN (625 1975);
DISPLAY INVISIBLE (625 1975);
FORCEPROP 1 LAST COMMENT_BODY TRUE
J 0
(275 2000);
DISPLAY 1.170213 (275 2000);
PAINT GREEN (275 2000);
DISPLAY INVISIBLE (275 2000);
FORCEADD OFFPAGE..2
(300 2000);
FORCEPROP 2 LAST $XR0 96 
J 0
(489 2000);
DISPLAY 0.638298 (489 2000);
PAINT MONO (489 2000);
FORCEPROP 2 LAST CDS_LIB mstr_standard
J 0
(300 2000);
PAINT ORANGE (300 2000);
DISPLAY INVISIBLE (300 2000);
FORCEPROP 2 LAST PATH I162
J 0
(500 2050);
DISPLAY 1.021277 (500 2050);
PAINT ORANGE (500 2050);
DISPLAY INVISIBLE (500 2050);
FORCEPROP 1 LAST OFFPAGE TRUE
J 0
(625 1875);
DISPLAY 1.170213 (625 1875);
PAINT GREEN (625 1875);
DISPLAY INVISIBLE (625 1875);
FORCEPROP 1 LAST COMMENT_BODY TRUE
J 0
(255 1905);
DISPLAY 1.170213 (255 1905);
PAINT GREEN (255 1905);
DISPLAY INVISIBLE (255 1905);
FORCEADD OFFPAGE..2
(300 1850);
FORCEPROP 2 LAST $XR0 102 
J 0
(489 1850);
DISPLAY 0.638298 (489 1850);
PAINT MONO (489 1850);
FORCEPROP 2 LAST CDS_LIB mstr_standard
J 2
(300 1850);
PAINT ORANGE (300 1850);
DISPLAY INVISIBLE (300 1850);
FORCEPROP 2 LAST PATH I165
J 0
(950 1900);
DISPLAY 1.021277 (950 1900);
PAINT ORANGE (950 1900);
DISPLAY INVISIBLE (950 1900);
FORCEPROP 1 LAST OFFPAGE TRUE
J 0
(625 1725);
DISPLAY 1.170213 (625 1725);
PAINT GREEN (625 1725);
DISPLAY INVISIBLE (625 1725);
FORCEPROP 1 LAST COMMENT_BODY TRUE
J 0
(255 1755);
DISPLAY 1.170213 (255 1755);
PAINT GREEN (255 1755);
DISPLAY INVISIBLE (255 1755);
FORCEADD OFFPAGE..4
(300 1700);
FORCEPROP 2 LAST $XR2 144 
J 0
(696 1700);
DISPLAY 0.638298 (696 1700);
PAINT MONO (696 1700);
FORCEPROP 2 LAST $XR1 118 
J 0
(576 1700);
DISPLAY 0.638298 (576 1700);
PAINT MONO (576 1700);
FORCEPROP 2 LAST $XR0 21 
J 0
(486 1700);
DISPLAY 0.638298 (486 1700);
PAINT MONO (486 1700);
FORCEPROP 2 LAST CDS_LIB mstr_standard
J 0
(300 1700);
PAINT ORANGE (300 1700);
DISPLAY INVISIBLE (300 1700);
FORCEPROP 2 LAST PATH I167
J 0
(925 1750);
DISPLAY 1.021277 (925 1750);
PAINT ORANGE (925 1750);
DISPLAY INVISIBLE (925 1750);
FORCEPROP 1 LAST OFFPAGE TRUE
J 0
(625 1575);
DISPLAY 1.170213 (625 1575);
PAINT GREEN (625 1575);
DISPLAY INVISIBLE (625 1575);
FORCEPROP 1 LAST COMMENT_BODY TRUE
J 0
(275 1600);
DISPLAY 1.170213 (275 1600);
PAINT GREEN (275 1600);
DISPLAY INVISIBLE (275 1600);
FORCEADD OFFPAGE..4
(300 1600);
FORCEPROP 2 LAST $XR1 113 
J 0
(576 1600);
DISPLAY 0.638298 (576 1600);
PAINT MONO (576 1600);
FORCEPROP 2 LAST $XR0 55 
J 0
(486 1600);
DISPLAY 0.638298 (486 1600);
PAINT MONO (486 1600);
FORCEPROP 2 LAST CDS_LIB mstr_standard
J 0
(300 1600);
PAINT ORANGE (300 1600);
DISPLAY INVISIBLE (300 1600);
FORCEPROP 2 LAST PATH I168
J 0
(500 1650);
DISPLAY 1.021277 (500 1650);
PAINT ORANGE (500 1650);
DISPLAY INVISIBLE (500 1650);
FORCEPROP 1 LAST OFFPAGE TRUE
J 0
(625 1475);
DISPLAY 1.170213 (625 1475);
PAINT GREEN (625 1475);
DISPLAY INVISIBLE (625 1475);
FORCEPROP 1 LAST COMMENT_BODY TRUE
J 0
(275 1500);
DISPLAY 1.170213 (275 1500);
PAINT GREEN (275 1500);
DISPLAY INVISIBLE (275 1500);
FORCEADD OFFPAGE..4
(300 1300);
FORCEPROP 2 LAST $XR2 247 
J 0
(696 1300);
DISPLAY 0.638298 (696 1300);
PAINT MONO (696 1300);
FORCEPROP 2 LAST $XR1 144 
J 0
(576 1300);
DISPLAY 0.638298 (576 1300);
PAINT MONO (576 1300);
FORCEPROP 2 LAST $XR0 92 
J 0
(486 1300);
DISPLAY 0.638298 (486 1300);
PAINT MONO (486 1300);
FORCEPROP 2 LAST CDS_LIB mstr_standard
J 0
(300 1300);
PAINT ORANGE (300 1300);
DISPLAY INVISIBLE (300 1300);
FORCEPROP 2 LAST PATH I171
J 0
(500 1350);
DISPLAY 1.021277 (500 1350);
PAINT ORANGE (500 1350);
DISPLAY INVISIBLE (500 1350);
FORCEPROP 1 LAST OFFPAGE TRUE
J 0
(625 1175);
DISPLAY 1.170213 (625 1175);
PAINT GREEN (625 1175);
DISPLAY INVISIBLE (625 1175);
FORCEPROP 1 LAST COMMENT_BODY TRUE
J 0
(275 1200);
DISPLAY 1.170213 (275 1200);
PAINT GREEN (275 1200);
DISPLAY INVISIBLE (275 1200);
FORCEADD LCMXO2_A..4
(-1950 2950);
FORCEPROP 2 LASTPIN (-2550 3750) $PN F1
J 2
(-2560 3760);
DISPLAY 0.617021 (-2560 3760);
PAINT ORANGE (-2560 3760);
FORCEPROP 2 LASTPIN (-2550 3800) $PN F3
J 2
(-2560 3810);
DISPLAY 0.617021 (-2560 3810);
PAINT ORANGE (-2560 3810);
FORCEPROP 2 LASTPIN (-2550 3950) $PN F4
J 2
(-2560 3960);
DISPLAY 0.617021 (-2560 3960);
PAINT ORANGE (-2560 3960);
FORCEPROP 2 LASTPIN (-2550 3900) $PN G6
J 2
(-2560 3910);
DISPLAY 0.617021 (-2560 3910);
PAINT ORANGE (-2560 3910);
FORCEPROP 2 LASTPIN (-1350 4450) $PN R3
J 0
(-1340 4460);
DISPLAY 0.617021 (-1340 4460);
PAINT ORANGE (-1340 4460);
FORCEPROP 2 LASTPIN (-1350 4500) $PN T2
J 0
(-1340 4510);
DISPLAY 0.617021 (-1340 4510);
PAINT ORANGE (-1340 4510);
FORCEPROP 2 LASTPIN (-1350 4550) $PN T4
J 0
(-1340 4560);
DISPLAY 0.617021 (-1340 4560);
PAINT ORANGE (-1340 4560);
FORCEPROP 2 LASTPIN (-1350 4150) $PN T5
J 0
(-1340 4160);
DISPLAY 0.617021 (-1340 4160);
PAINT ORANGE (-1340 4160);
FORCEPROP 2 LASTPIN (-1350 3800) $PN N6
J 0
(-1340 3810);
DISPLAY 0.617021 (-1340 3810);
PAINT ORANGE (-1340 3810);
FORCEPROP 2 LASTPIN (-2550 4550) $PN D3
J 2
(-2560 4560);
DISPLAY 0.617021 (-2560 4560);
PAINT ORANGE (-2560 4560);
FORCEPROP 2 LASTPIN (-2550 1500) $PN N3
J 2
(-2560 1510);
DISPLAY 0.617021 (-2560 1510);
PAINT ORANGE (-2560 1510);
FORCEPROP 2 LASTPIN (-2550 2800) $PN J2
J 2
(-2560 2810);
DISPLAY 0.617021 (-2560 2810);
PAINT ORANGE (-2560 2810);
FORCEPROP 2 LASTPIN (-2550 1700) $PN N2
J 2
(-2560 1710);
DISPLAY 0.617021 (-2560 1710);
PAINT ORANGE (-2560 1710);
FORCEPROP 1 LAST PART_NUMBER H63395-001
J 0
(-2500 1150);
DISPLAY 0.617021 (-2500 1150);
PAINT BLUE (-2500 1150);
FORCEPROP 2 LASTPIN (-2550 1450) $PN R1
J 2
(-2560 1460);
DISPLAY 0.617021 (-2560 1460);
PAINT ORANGE (-2560 1460);
FORCEPROP 2 LASTPIN (-2550 1550) $PN M2
J 2
(-2560 1560);
DISPLAY 0.617021 (-2560 1560);
PAINT ORANGE (-2560 1560);
FORCEPROP 2 LASTPIN (-2550 2900) $PN J3
J 2
(-2560 2910);
DISPLAY 0.617021 (-2560 2910);
PAINT ORANGE (-2560 2910);
FORCEPROP 2 LASTPIN (-1350 3650) $PN R7
J 0
(-1340 3660);
DISPLAY 0.617021 (-1340 3660);
PAINT ORANGE (-1340 3660);
FORCEPROP 2 LASTPIN (-1350 4300) $PN P5
J 0
(-1340 4310);
DISPLAY 0.617021 (-1340 4310);
PAINT ORANGE (-1340 4310);
FORCEPROP 1 LAST MATERIAL IC
J 0
(-2500 4731);
DISPLAY 0.617021 (-2500 4731);
PAINT SKYBLUE (-2500 4731);
FORCEPROP 2 LASTPIN (-2550 1400) $PN P2
J 2
(-2560 1410);
DISPLAY 0.617021 (-2560 1410);
PAINT ORANGE (-2560 1410);
FORCEPROP 2 LASTPIN (-2550 1650) $PN P1
J 2
(-2560 1660);
DISPLAY 0.617021 (-2560 1660);
PAINT ORANGE (-2560 1660);
FORCEPROP 2 LASTPIN (-2550 1750) $PN N1
J 2
(-2560 1760);
DISPLAY 0.617021 (-2560 1760);
PAINT ORANGE (-2560 1760);
FORCEPROP 2 LASTPIN (-2550 1800) $PN M3
J 2
(-2560 1810);
DISPLAY 0.617021 (-2560 1810);
PAINT ORANGE (-2560 1810);
FORCEPROP 2 LASTPIN (-2550 1900) $PN L4
J 2
(-2560 1910);
DISPLAY 0.617021 (-2560 1910);
PAINT ORANGE (-2560 1910);
FORCEPROP 2 LASTPIN (-2550 2000) $PN M1
J 2
(-2560 2010);
DISPLAY 0.617021 (-2560 2010);
PAINT ORANGE (-2560 2010);
FORCEPROP 2 LASTPIN (-2550 2050) $PN L2
J 2
(-2560 2060);
DISPLAY 0.617021 (-2560 2060);
PAINT ORANGE (-2560 2060);
FORCEPROP 2 LASTPIN (-2550 2150) $PN L5
J 2
(-2560 2160);
DISPLAY 0.617021 (-2560 2160);
PAINT ORANGE (-2560 2160);
FORCEPROP 2 LASTPIN (-2550 2200) $PN K4
J 2
(-2560 2210);
DISPLAY 0.617021 (-2560 2210);
PAINT ORANGE (-2560 2210);
FORCEPROP 2 LASTPIN (-2550 2250) $PN L3
J 2
(-2560 2260);
DISPLAY 0.617021 (-2560 2260);
PAINT ORANGE (-2560 2260);
FORCEPROP 2 LASTPIN (-2550 2300) $PN L1
J 2
(-2560 2310);
DISPLAY 0.617021 (-2560 2310);
PAINT ORANGE (-2560 2310);
FORCEPROP 2 LASTPIN (-2550 2400) $PN K6
J 2
(-2560 2410);
DISPLAY 0.617021 (-2560 2410);
PAINT ORANGE (-2560 2410);
FORCEPROP 2 LASTPIN (-2550 2450) $PN J5
J 2
(-2560 2460);
DISPLAY 0.617021 (-2560 2460);
PAINT ORANGE (-2560 2460);
FORCEPROP 2 LASTPIN (-2550 2500) $PN K2
J 2
(-2560 2510);
DISPLAY 0.617021 (-2560 2510);
PAINT ORANGE (-2560 2510);
FORCEPROP 2 LASTPIN (-2550 2550) $PN K3
J 2
(-2560 2560);
DISPLAY 0.617021 (-2560 2560);
PAINT ORANGE (-2560 2560);
FORCEPROP 2 LASTPIN (-2550 2700) $PN H5
J 2
(-2560 2710);
DISPLAY 0.617021 (-2560 2710);
PAINT ORANGE (-2560 2710);
FORCEPROP 2 LASTPIN (-2550 2750) $PN K1
J 2
(-2560 2760);
DISPLAY 0.617021 (-2560 2760);
PAINT ORANGE (-2560 2760);
FORCEPROP 2 LASTPIN (-2550 3000) $PN H1
J 2
(-2560 3010);
DISPLAY 0.617021 (-2560 3010);
PAINT ORANGE (-2560 3010);
FORCEPROP 2 LASTPIN (-2550 3250) $PN H2
J 2
(-2560 3260);
DISPLAY 0.617021 (-2560 3260);
PAINT ORANGE (-2560 3260);
FORCEPROP 2 LASTPIN (-2550 3450) $PN F5
J 2
(-2560 3460);
DISPLAY 0.617021 (-2560 3460);
PAINT ORANGE (-2560 3460);
FORCEPROP 2 LASTPIN (-2550 3650) $PN G4
J 2
(-2560 3660);
DISPLAY 0.617021 (-2560 3660);
PAINT ORANGE (-2560 3660);
FORCEPROP 2 LASTPIN (-2550 4000) $PN F2
J 2
(-2560 4010);
DISPLAY 0.617021 (-2560 4010);
PAINT ORANGE (-2560 4010);
FORCEPROP 2 LASTPIN (-2550 4250) $PN E3
J 2
(-2560 4260);
DISPLAY 0.617021 (-2560 4260);
PAINT ORANGE (-2560 4260);
FORCEPROP 2 LASTPIN (-2550 4300) $PN E2
J 2
(-2560 4310);
DISPLAY 0.617021 (-2560 4310);
PAINT ORANGE (-2560 4310);
FORCEPROP 2 LASTPIN (-2550 4400) $PN C2
J 2
(-2560 4410);
DISPLAY 0.617021 (-2560 4410);
PAINT ORANGE (-2560 4410);
FORCEPROP 2 LASTPIN (-2550 4500) $PN D1
J 2
(-2560 4510);
DISPLAY 0.617021 (-2560 4510);
PAINT ORANGE (-2560 4510);
FORCEPROP 2 LASTPIN (-1350 1300) $PN R14
J 0
(-1340 1310);
DISPLAY 0.617021 (-1340 1310);
PAINT ORANGE (-1340 1310);
FORCEPROP 2 LASTPIN (-1350 1350) $PN T15
J 0
(-1340 1360);
DISPLAY 0.617021 (-1340 1360);
PAINT ORANGE (-1340 1360);
FORCEPROP 2 LASTPIN (-1350 1400) $PN P13
J 0
(-1340 1410);
DISPLAY 0.617021 (-1340 1410);
PAINT ORANGE (-1340 1410);
FORCEPROP 2 LASTPIN (-1350 1450) $PN R12
J 0
(-1340 1460);
DISPLAY 0.617021 (-1340 1460);
PAINT ORANGE (-1340 1460);
FORCEPROP 2 LASTPIN (-1350 1550) $PN T13
J 0
(-1340 1560);
DISPLAY 0.617021 (-1340 1560);
PAINT ORANGE (-1340 1560);
FORCEPROP 2 LASTPIN (-1350 1600) $PN P12
J 0
(-1340 1610);
DISPLAY 0.617021 (-1340 1610);
PAINT ORANGE (-1340 1610);
FORCEPROP 2 LASTPIN (-1350 1750) $PN R13
J 0
(-1340 1760);
DISPLAY 0.617021 (-1340 1760);
PAINT ORANGE (-1340 1760);
FORCEPROP 2 LASTPIN (-1350 1800) $PN T12
J 0
(-1340 1810);
DISPLAY 0.617021 (-1340 1810);
PAINT ORANGE (-1340 1810);
FORCEPROP 2 LASTPIN (-1350 1950) $PN N11
J 0
(-1340 1960);
DISPLAY 0.617021 (-1340 1960);
PAINT ORANGE (-1340 1960);
FORCEPROP 2 LASTPIN (-1350 2000) $PN M10
J 0
(-1340 2010);
DISPLAY 0.617021 (-1340 2010);
PAINT ORANGE (-1340 2010);
FORCEPROP 2 LASTPIN (-1350 2050) $PN P11
J 0
(-1340 2060);
DISPLAY 0.617021 (-1340 2060);
PAINT ORANGE (-1340 2060);
FORCEPROP 2 LASTPIN (-1350 2100) $PN T11
J 0
(-1340 2110);
DISPLAY 0.617021 (-1340 2110);
PAINT ORANGE (-1340 2110);
FORCEPROP 2 LASTPIN (-1350 2200) $PN M11
J 0
(-1340 2210);
DISPLAY 0.617021 (-1340 2210);
PAINT ORANGE (-1340 2210);
FORCEPROP 2 LASTPIN (-1350 2250) $PN N10
J 0
(-1340 2260);
DISPLAY 0.617021 (-1340 2260);
PAINT ORANGE (-1340 2260);
FORCEPROP 2 LASTPIN (-1350 2300) $PN R10
J 0
(-1340 2310);
DISPLAY 0.617021 (-1340 2310);
PAINT ORANGE (-1340 2310);
FORCEPROP 2 LASTPIN (-1350 2550) $PN T10
J 0
(-1340 2560);
DISPLAY 0.617021 (-1340 2560);
PAINT ORANGE (-1340 2560);
FORCEPROP 2 LASTPIN (-1350 2600) $PN R9
J 0
(-1340 2610);
DISPLAY 0.617021 (-1340 2610);
PAINT ORANGE (-1340 2610);
FORCEPROP 2 LASTPIN (-1350 2700) $PN N9
J 0
(-1340 2710);
DISPLAY 0.617021 (-1340 2710);
PAINT ORANGE (-1340 2710);
FORCEPROP 2 LASTPIN (-1350 2750) $PN M8
J 0
(-1340 2760);
DISPLAY 0.617021 (-1340 2760);
PAINT ORANGE (-1340 2760);
FORCEPROP 2 LASTPIN (-1350 2800) $PN P9
J 0
(-1340 2810);
DISPLAY 0.617021 (-1340 2810);
PAINT ORANGE (-1340 2810);
FORCEPROP 2 LASTPIN (-1350 2850) $PN T9
J 0
(-1340 2860);
DISPLAY 0.617021 (-1340 2860);
PAINT ORANGE (-1340 2860);
FORCEPROP 2 LASTPIN (-1350 3000) $PN L9
J 0
(-1340 3010);
DISPLAY 0.617021 (-1340 3010);
PAINT ORANGE (-1340 3010);
FORCEPROP 2 LASTPIN (-1350 3050) $PN N8
J 0
(-1340 3060);
DISPLAY 0.617021 (-1340 3060);
PAINT ORANGE (-1340 3060);
FORCEPROP 2 LASTPIN (-1350 3100) $PN T8
J 0
(-1340 3110);
DISPLAY 0.617021 (-1340 3110);
PAINT ORANGE (-1340 3110);
FORCEPROP 2 LASTPIN (-1350 3150) $PN P8
J 0
(-1340 3160);
DISPLAY 0.617021 (-1340 3160);
PAINT ORANGE (-1340 3160);
FORCEPROP 2 LASTPIN (-1350 3250) $PN L8
J 0
(-1340 3260);
DISPLAY 0.617021 (-1340 3260);
PAINT ORANGE (-1340 3260);
FORCEPROP 2 LASTPIN (-1350 3300) $PN M6
J 0
(-1340 3310);
DISPLAY 0.617021 (-1340 3310);
PAINT ORANGE (-1340 3310);
FORCEPROP 2 LASTPIN (-1350 3350) $PN R8
J 0
(-1340 3360);
DISPLAY 0.617021 (-1340 3360);
PAINT ORANGE (-1340 3360);
FORCEPROP 2 LASTPIN (-1350 3500) $PN N7
J 0
(-1340 3510);
DISPLAY 0.617021 (-1340 3510);
PAINT ORANGE (-1340 3510);
FORCEPROP 2 LASTPIN (-1350 3600) $PN P7
J 0
(-1340 3610);
DISPLAY 0.617021 (-1340 3610);
PAINT ORANGE (-1340 3610);
FORCEPROP 2 LASTPIN (-1350 3750) $PN L7
J 0
(-1340 3760);
DISPLAY 0.617021 (-1340 3760);
PAINT ORANGE (-1340 3760);
FORCEPROP 2 LASTPIN (-1350 4000) $PN R4
J 0
(-1340 4010);
DISPLAY 0.617021 (-1340 4010);
PAINT ORANGE (-1340 4010);
FORCEPROP 2 LASTPIN (-1350 4050) $PN T3
J 0
(-1340 4060);
DISPLAY 0.617021 (-1340 4060);
PAINT ORANGE (-1340 4060);
FORCEPROP 2 LASTPIN (-1350 4100) $PN R6
J 0
(-1340 4110);
DISPLAY 0.617021 (-1340 4110);
PAINT ORANGE (-1340 4110);
FORCEPROP 2 LASTPIN (-1350 4600) $PN P4
J 0
(-1340 4610);
DISPLAY 0.617021 (-1340 4610);
PAINT ORANGE (-1340 4610);
FORCEPROP 2 LASTPIN (-2550 3400) $PN H6
J 2
(-2560 3410);
DISPLAY 0.617021 (-2560 3410);
PAINT ORANGE (-2560 3410);
FORCEPROP 2 LASTPIN (-1350 2500) $PN M9
J 0
(-1340 2510);
DISPLAY 0.617021 (-1340 2510);
PAINT ORANGE (-1340 2510);
FORCEPROP 2 LASTPIN (-1350 2450) $PN L10
J 0
(-1340 2460);
DISPLAY 0.617021 (-1340 2460);
PAINT ORANGE (-1340 2460);
FORCEPROP 2 LASTPIN (-1350 2350) $PN P10
J 0
(-1340 2360);
DISPLAY 0.617021 (-1340 2360);
PAINT ORANGE (-1340 2360);
FORCEPROP 2 LASTPIN (-2550 2950) $PN J1
J 2
(-2560 2960);
DISPLAY 0.617021 (-2560 2960);
PAINT ORANGE (-2560 2960);
FORCEPROP 2 LASTPIN (-2550 3150) $PN J6
J 2
(-2560 3160);
DISPLAY 0.617021 (-2560 3160);
PAINT ORANGE (-2560 3160);
FORCEPROP 2 LASTPIN (-1350 1850) $PN R11
J 0
(-1340 1860);
DISPLAY 0.617021 (-1340 1860);
PAINT ORANGE (-1340 1860);
FORCEPROP 2 LASTPIN (-2550 1950) $PN K5
J 2
(-2560 1960);
DISPLAY 0.617021 (-2560 1960);
PAINT ORANGE (-2560 1960);
FORCEPROP 2 LASTPIN (-1350 1700) $PN T14
J 0
(-1340 1710);
DISPLAY 0.617021 (-1340 1710);
PAINT ORANGE (-1340 1710);
FORCEPROP 2 LASTPIN (-1350 3850) $PN T6
J 0
(-1340 3860);
DISPLAY 0.617021 (-1340 3860);
PAINT ORANGE (-1340 3860);
FORCEPROP 2 LASTPIN (-1350 3900) $PN P6
J 0
(-1340 3910);
DISPLAY 0.617021 (-1340 3910);
PAINT ORANGE (-1340 3910);
FORCEPROP 2 LASTPIN (-2550 2650) $PN J4
J 2
(-2560 2660);
DISPLAY 0.617021 (-2560 2660);
PAINT ORANGE (-2560 2660);
FORCEPROP 2 LASTPIN (-2550 3550) $PN G2
J 2
(-2560 3560);
DISPLAY 0.617021 (-2560 3560);
PAINT ORANGE (-2560 3560);
FORCEPROP 2 LASTPIN (-2550 3500) $PN G3
J 2
(-2560 3510);
DISPLAY 0.617021 (-2560 3510);
PAINT ORANGE (-2560 3510);
FORCEPROP 2 LASTPIN (-2550 3200) $PN H4
J 2
(-2560 3210);
DISPLAY 0.617021 (-2560 3210);
PAINT ORANGE (-2560 3210);
FORCEPROP 2 LASTPIN (-2550 3050) $PN H3
J 2
(-2560 3060);
DISPLAY 0.617021 (-2560 3060);
PAINT ORANGE (-2560 3060);
FORCEPROP 2 LASTPIN (-2550 3300) $PN G1
J 2
(-2560 3310);
DISPLAY 0.617021 (-2560 3310);
PAINT ORANGE (-2560 3310);
FORCEPROP 2 LASTPIN (-2550 4450) $PN B1
J 2
(-2560 4460);
DISPLAY 0.617021 (-2560 4460);
PAINT ORANGE (-2560 4460);
FORCEPROP 1 LAST LOCATION U8D7
J 0
(-2500 4781);
DISPLAY 0.617021 (-2500 4781);
PAINT AQUA (-2500 4781);
FORCEPROP 2 LASTPIN (-1350 4350) $PN R5
J 0
(-1340 4360);
DISPLAY 0.617021 (-1340 4360);
PAINT ORANGE (-1340 4360);
FORCEPROP 2 LASTPIN (-2550 4050) $PN E1
J 2
(-2560 4060);
DISPLAY 0.617021 (-2560 4060);
PAINT ORANGE (-2560 4060);
FORCEPROP 2 LASTPIN (-1350 3550) $PN M7
J 0
(-1340 3560);
DISPLAY 0.617021 (-1340 3560);
PAINT ORANGE (-1340 3560);
FORCEPROP 2 LASTPIN (-1350 3400) $PN T7
J 0
(-1340 3410);
DISPLAY 0.617021 (-1340 3410);
PAINT ORANGE (-1340 3410);
FORCEPROP 2 LASTPIN (-2550 3700) $PN G5
J 2
(-2560 3710);
DISPLAY 0.617021 (-2560 3710);
PAINT ORANGE (-2560 3710);
FORCEPROP 2 LASTPIN (-2550 4200) $PN C1
J 2
(-2560 4210);
DISPLAY 0.617021 (-2560 4210);
PAINT ORANGE (-2560 4210);
FORCEPROP 2 LASTPIN (-2550 4150) $PN D2
J 2
(-2560 4160);
DISPLAY 0.617021 (-2560 4160);
PAINT ORANGE (-2560 4160);
FORCEPROP 1 LAST PACK_TYPE 256BGA
J 0
(-2500 4825);
PAINT SKYBLUE (-2500 4825);
DISPLAY INVISIBLE (-2500 4825);
FORCEPROP 0 LAST ROOM CPLD
J 0
(-2500 4900);
DISPLAY 1.361702 (-2500 4900);
PAINT ORANGE (-2500 4900);
DISPLAY INVISIBLE (-2500 4900);
FORCEPROP 2 LAST SEC_TYPE 256BGA
J 0
(-2500 4825);
DISPLAY 1.021277 (-2500 4825);
PAINT ORANGE (-2500 4825);
DISPLAY INVISIBLE (-2500 4825);
FORCEPROP 2 LAST SEC 1
J 0
(-2500 4825);
DISPLAY 0.680851 (-2500 4825);
PAINT MONO (-2500 4825);
DISPLAY INVISIBLE (-2500 4825);
FORCEPROP 2 LAST CDS_LIB mstr_memory
J 0
(-1950 2950);
PAINT ORANGE (-1950 2950);
DISPLAY INVISIBLE (-1950 2950);
FORCEPROP 1 LAST CDS_LMAN_SYM_OUTLINE -550,1750,550,-1750
J 0
(-1950 2950);
DISPLAY 0.468085 (-1950 2950);
PAINT GREEN (-1950 2950);
DISPLAY INVISIBLE (-1950 2950);
FORCEPROP 1 LAST PATH I179
J 0
(-1524 4726);
PAINT GREEN (-1524 4726);
DISPLAY INVISIBLE (-1524 4726);
FORCEPROP 2 LAST CDS_LOCATION U8D7
J 0
(-2500 4781);
DISPLAY 0.617021 (-2500 4781);
PAINT AQUA (-2500 4781);
DISPLAY INVISIBLE (-2500 4781);
FORCEPROP 0 LAST BOM_COST CPLD
J 0
(-2500 5000);
DISPLAY 1.361702 (-2500 5000);
PAINT ORANGE (-2500 5000);
DISPLAY INVISIBLE (-2500 5000);
FORCEADD OFFPAGE..2
(300 1350);
FORCEPROP 2 LAST $XR0 96 
J 0
(489 1350);
DISPLAY 0.638298 (489 1350);
PAINT MONO (489 1350);
FORCEPROP 2 LAST CDS_LIB mstr_standard
J 2
(300 1350);
PAINT ORANGE (300 1350);
DISPLAY INVISIBLE (300 1350);
FORCEPROP 2 LAST PATH I220
J 0
(475 1425);
DISPLAY 1.021277 (475 1425);
PAINT ORANGE (475 1425);
DISPLAY INVISIBLE (475 1425);
FORCEPROP 1 LAST OFFPAGE TRUE
J 0
(625 1225);
DISPLAY 1.170213 (625 1225);
PAINT GREEN (625 1225);
DISPLAY INVISIBLE (625 1225);
FORCEPROP 1 LAST COMMENT_BODY TRUE
J 0
(255 1255);
DISPLAY 1.170213 (255 1255);
PAINT GREEN (255 1255);
DISPLAY INVISIBLE (255 1255);
FORCEADD OFFPAGE..4
(300 1450);
FORCEPROP 2 LAST $XR0 55 
J 0
(486 1450);
DISPLAY 0.638298 (486 1450);
PAINT MONO (486 1450);
FORCEPROP 2 LAST CDS_LIB mstr_standard
J 0
(300 1450);
PAINT ORANGE (300 1450);
DISPLAY INVISIBLE (300 1450);
FORCEPROP 2 LAST PATH I221
J 0
(475 1525);
DISPLAY 1.021277 (475 1525);
PAINT ORANGE (475 1525);
DISPLAY INVISIBLE (475 1525);
FORCEPROP 1 LAST OFFPAGE TRUE
J 0
(625 1325);
DISPLAY 1.170213 (625 1325);
PAINT GREEN (625 1325);
DISPLAY INVISIBLE (625 1325);
FORCEPROP 1 LAST COMMENT_BODY TRUE
J 0
(275 1350);
DISPLAY 1.170213 (275 1350);
PAINT GREEN (275 1350);
DISPLAY INVISIBLE (275 1350);
FORCEADD OFFPAGE..4
(300 1800);
FORCEPROP 2 LAST $XR3 146 
J 0
(816 1800);
DISPLAY 0.638298 (816 1800);
PAINT MONO (816 1800);
FORCEPROP 2 LAST $XR2 118 
J 0
(696 1800);
DISPLAY 0.638298 (696 1800);
PAINT MONO (696 1800);
FORCEPROP 2 LAST $XR1 112 
J 0
(576 1800);
DISPLAY 0.638298 (576 1800);
PAINT MONO (576 1800);
FORCEPROP 2 LAST $XR0 55 
J 0
(486 1800);
DISPLAY 0.638298 (486 1800);
PAINT MONO (486 1800);
FORCEPROP 2 LAST CDS_LIB mstr_standard
J 2
(300 1800);
PAINT ORANGE (300 1800);
DISPLAY INVISIBLE (300 1800);
FORCEPROP 2 LAST PATH I224
J 0
(475 1875);
DISPLAY 1.021277 (475 1875);
PAINT ORANGE (475 1875);
DISPLAY INVISIBLE (475 1875);
FORCEPROP 1 LAST OFFPAGE TRUE
J 0
(625 1675);
DISPLAY 1.170213 (625 1675);
PAINT GREEN (625 1675);
DISPLAY INVISIBLE (625 1675);
FORCEPROP 1 LAST COMMENT_BODY TRUE
J 0
(275 1700);
DISPLAY 1.170213 (275 1700);
PAINT GREEN (275 1700);
DISPLAY INVISIBLE (275 1700);
FORCEADD OFFPAGE..4
(300 1950);
FORCEPROP 2 LAST $XR1 144 
J 0
(606 1950);
DISPLAY 0.638298 (606 1950);
PAINT MONO (606 1950);
FORCEPROP 2 LAST $XR0 111 
J 0
(486 1950);
DISPLAY 0.638298 (486 1950);
PAINT MONO (486 1950);
FORCEPROP 2 LAST CDS_LIB mstr_standard
J 2
(300 1950);
PAINT ORANGE (300 1950);
DISPLAY INVISIBLE (300 1950);
FORCEPROP 2 LAST PATH I225
J 0
(475 2025);
DISPLAY 1.021277 (475 2025);
PAINT ORANGE (475 2025);
DISPLAY INVISIBLE (475 2025);
FORCEPROP 1 LAST OFFPAGE TRUE
J 0
(625 1825);
DISPLAY 1.170213 (625 1825);
PAINT GREEN (625 1825);
DISPLAY INVISIBLE (625 1825);
FORCEPROP 1 LAST COMMENT_BODY TRUE
J 0
(275 1850);
DISPLAY 1.170213 (275 1850);
PAINT GREEN (275 1850);
DISPLAY INVISIBLE (275 1850);
FORCEADD OFFPAGE..4
(300 2200);
FORCEPROP 2 LAST $XR0 111 
J 0
(486 2200);
DISPLAY 0.638298 (486 2200);
PAINT MONO (486 2200);
FORCEPROP 2 LAST CDS_LIB mstr_standard
J 0
(300 2200);
PAINT ORANGE (300 2200);
DISPLAY INVISIBLE (300 2200);
FORCEPROP 2 LAST PATH I226
J 0
(475 2275);
DISPLAY 1.021277 (475 2275);
PAINT ORANGE (475 2275);
DISPLAY INVISIBLE (475 2275);
FORCEPROP 1 LAST OFFPAGE TRUE
J 0
(625 2075);
DISPLAY 1.170213 (625 2075);
PAINT GREEN (625 2075);
DISPLAY INVISIBLE (625 2075);
FORCEPROP 1 LAST COMMENT_BODY TRUE
J 0
(275 2100);
DISPLAY 1.170213 (275 2100);
PAINT GREEN (275 2100);
DISPLAY INVISIBLE (275 2100);
FORCEADD OFFPAGE..2
(300 2300);
FORCEPROP 2 LAST $XR0 190 
J 0
(489 2300);
DISPLAY 0.638298 (489 2300);
PAINT MONO (489 2300);
FORCEPROP 2 LAST CDS_LIB mstr_standard
J 2
(300 2300);
PAINT ORANGE (300 2300);
DISPLAY INVISIBLE (300 2300);
FORCEPROP 2 LAST PATH I227
J 0
(475 2375);
DISPLAY 1.021277 (475 2375);
PAINT ORANGE (475 2375);
DISPLAY INVISIBLE (475 2375);
FORCEPROP 1 LAST OFFPAGE TRUE
J 0
(625 2175);
DISPLAY 1.170213 (625 2175);
PAINT GREEN (625 2175);
DISPLAY INVISIBLE (625 2175);
FORCEPROP 1 LAST COMMENT_BODY TRUE
J 0
(255 2205);
DISPLAY 1.170213 (255 2205);
PAINT GREEN (255 2205);
DISPLAY INVISIBLE (255 2205);
FORCEADD OFFPAGE..2
(300 2750);
FORCEPROP 2 LAST $XR0 193 
J 0
(489 2750);
DISPLAY 0.638298 (489 2750);
PAINT MONO (489 2750);
FORCEPROP 2 LAST CDS_LIB mstr_standard
J 0
(300 2750);
PAINT ORANGE (300 2750);
DISPLAY INVISIBLE (300 2750);
FORCEPROP 2 LAST PATH I231
J 0
(475 2825);
DISPLAY 1.021277 (475 2825);
PAINT ORANGE (475 2825);
DISPLAY INVISIBLE (475 2825);
FORCEPROP 1 LAST OFFPAGE TRUE
J 0
(625 2625);
DISPLAY 1.170213 (625 2625);
PAINT GREEN (625 2625);
DISPLAY INVISIBLE (625 2625);
FORCEPROP 1 LAST COMMENT_BODY TRUE
J 0
(255 2655);
DISPLAY 1.170213 (255 2655);
PAINT GREEN (255 2655);
DISPLAY INVISIBLE (255 2655);
FORCEADD OFFPAGE..2
(300 3400);
FORCEPROP 2 LAST $XR0 213 
J 0
(489 3400);
DISPLAY 0.638298 (489 3400);
PAINT MONO (489 3400);
FORCEPROP 2 LAST PATH I234
J 0
(475 3475);
DISPLAY 1.021277 (475 3475);
PAINT ORANGE (475 3475);
DISPLAY INVISIBLE (475 3475);
FORCEPROP 2 LAST CDS_LIB mstr_standard
J 0
(300 3400);
PAINT ORANGE (300 3400);
DISPLAY INVISIBLE (300 3400);
FORCEPROP 1 LAST OFFPAGE TRUE
J 0
(625 3275);
DISPLAY 1.170213 (625 3275);
PAINT GREEN (625 3275);
DISPLAY INVISIBLE (625 3275);
FORCEPROP 1 LAST COMMENT_BODY TRUE
J 0
(255 3305);
DISPLAY 1.170213 (255 3305);
PAINT GREEN (255 3305);
DISPLAY INVISIBLE (255 3305);
FORCEADD OFFPAGE..2
(300 3550);
FORCEPROP 2 LAST $XR0 211 
J 0
(489 3550);
DISPLAY 0.638298 (489 3550);
PAINT MONO (489 3550);
FORCEPROP 2 LAST CDS_LIB mstr_standard
J 0
(300 3550);
PAINT ORANGE (300 3550);
DISPLAY INVISIBLE (300 3550);
FORCEPROP 2 LAST PATH I235
J 0
(475 3625);
DISPLAY 1.021277 (475 3625);
PAINT ORANGE (475 3625);
DISPLAY INVISIBLE (475 3625);
FORCEPROP 1 LAST OFFPAGE TRUE
J 0
(625 3425);
DISPLAY 1.170213 (625 3425);
PAINT GREEN (625 3425);
DISPLAY INVISIBLE (625 3425);
FORCEPROP 1 LAST COMMENT_BODY TRUE
J 0
(255 3455);
DISPLAY 1.170213 (255 3455);
PAINT GREEN (255 3455);
DISPLAY INVISIBLE (255 3455);
FORCEADD OFFPAGE..2
(300 3600);
FORCEPROP 2 LAST $XR0 193 
J 0
(489 3600);
DISPLAY 0.638298 (489 3600);
PAINT MONO (489 3600);
FORCEPROP 2 LAST CDS_LIB mstr_standard
J 0
(300 3600);
PAINT ORANGE (300 3600);
DISPLAY INVISIBLE (300 3600);
FORCEPROP 2 LAST PATH I236
J 0
(475 3675);
DISPLAY 1.021277 (475 3675);
PAINT ORANGE (475 3675);
DISPLAY INVISIBLE (475 3675);
FORCEPROP 1 LAST OFFPAGE TRUE
J 0
(625 3475);
DISPLAY 1.170213 (625 3475);
PAINT GREEN (625 3475);
DISPLAY INVISIBLE (625 3475);
FORCEPROP 1 LAST COMMENT_BODY TRUE
J 0
(255 3505);
DISPLAY 1.170213 (255 3505);
PAINT GREEN (255 3505);
DISPLAY INVISIBLE (255 3505);
FORCEADD OFFPAGE..4
(300 3800);
FORCEPROP 2 LAST $XR0 194 
J 0
(486 3800);
DISPLAY 0.638298 (486 3800);
PAINT MONO (486 3800);
FORCEPROP 2 LAST PATH I237
J 0
(475 3875);
DISPLAY 1.021277 (475 3875);
PAINT ORANGE (475 3875);
DISPLAY INVISIBLE (475 3875);
FORCEPROP 2 LAST CDS_LIB mstr_standard
J 0
(300 3800);
PAINT ORANGE (300 3800);
DISPLAY INVISIBLE (300 3800);
FORCEPROP 1 LAST OFFPAGE TRUE
J 0
(625 3675);
DISPLAY 1.170213 (625 3675);
PAINT GREEN (625 3675);
DISPLAY INVISIBLE (625 3675);
FORCEPROP 1 LAST COMMENT_BODY TRUE
J 0
(275 3700);
DISPLAY 1.170213 (275 3700);
PAINT GREEN (275 3700);
DISPLAY INVISIBLE (275 3700);
FORCEADD OFFPAGE..4
(300 4150);
FORCEPROP 2 LAST $XR0 193 
J 0
(486 4150);
DISPLAY 0.638298 (486 4150);
PAINT MONO (486 4150);
FORCEPROP 2 LAST CDS_LIB mstr_standard
J 0
(300 4150);
PAINT ORANGE (300 4150);
DISPLAY INVISIBLE (300 4150);
FORCEPROP 2 LAST PATH I239
J 0
(475 4225);
DISPLAY 1.021277 (475 4225);
PAINT ORANGE (475 4225);
DISPLAY INVISIBLE (475 4225);
FORCEPROP 1 LAST OFFPAGE TRUE
J 0
(625 4025);
DISPLAY 1.170213 (625 4025);
PAINT GREEN (625 4025);
DISPLAY INVISIBLE (625 4025);
FORCEPROP 1 LAST COMMENT_BODY TRUE
J 0
(275 4050);
DISPLAY 1.170213 (275 4050);
PAINT GREEN (275 4050);
DISPLAY INVISIBLE (275 4050);
FORCEADD OFFPAGE..4
(300 4300);
FORCEPROP 2 LAST $XR0 194 
J 0
(486 4300);
DISPLAY 0.638298 (486 4300);
PAINT MONO (486 4300);
FORCEPROP 2 LAST CDS_LIB mstr_standard
J 0
(300 4300);
PAINT ORANGE (300 4300);
DISPLAY INVISIBLE (300 4300);
FORCEPROP 2 LAST PATH I240
J 0
(475 4375);
DISPLAY 1.021277 (475 4375);
PAINT ORANGE (475 4375);
DISPLAY INVISIBLE (475 4375);
FORCEPROP 1 LAST OFFPAGE TRUE
J 0
(625 4175);
DISPLAY 1.170213 (625 4175);
PAINT GREEN (625 4175);
DISPLAY INVISIBLE (625 4175);
FORCEPROP 1 LAST COMMENT_BODY TRUE
J 0
(275 4200);
DISPLAY 1.170213 (275 4200);
PAINT GREEN (275 4200);
DISPLAY INVISIBLE (275 4200);
FORCEADD OFFPAGE..4
(300 4550);
FORCEPROP 2 LAST $XR0 206 
J 0
(486 4550);
DISPLAY 0.638298 (486 4550);
PAINT MONO (486 4550);
FORCEPROP 2 LAST CDS_LIB mstr_standard
J 0
(300 4550);
PAINT ORANGE (300 4550);
DISPLAY INVISIBLE (300 4550);
FORCEPROP 2 LAST PATH I241
J 0
(475 4625);
DISPLAY 1.021277 (475 4625);
PAINT ORANGE (475 4625);
DISPLAY INVISIBLE (475 4625);
FORCEPROP 1 LAST OFFPAGE TRUE
J 0
(625 4425);
DISPLAY 1.170213 (625 4425);
PAINT GREEN (625 4425);
DISPLAY INVISIBLE (625 4425);
FORCEPROP 1 LAST COMMENT_BODY TRUE
J 0
(275 4450);
DISPLAY 1.170213 (275 4450);
PAINT GREEN (275 4450);
DISPLAY INVISIBLE (275 4450);
FORCEADD OFFPAGE..4
R 2
(-4475 4400);
FORCEPROP 2 LAST $XR1 133 
J 0
(-4847 4400);
DISPLAY 0.638298 (-4847 4400);
PAINT MONO (-4847 4400);
FORCEPROP 2 LAST $XR0 119 
J 0
(-4727 4400);
DISPLAY 0.638298 (-4727 4400);
PAINT MONO (-4727 4400);
FORCEPROP 2 LAST PATH I243
J 0
(-4425 4475);
DISPLAY 1.021277 (-4425 4475);
PAINT ORANGE (-4425 4475);
DISPLAY INVISIBLE (-4425 4475);
FORCEPROP 2 LAST CDS_LIB mstr_standard
J 0
(-4475 4400);
PAINT ORANGE (-4475 4400);
DISPLAY INVISIBLE (-4475 4400);
FORCEPROP 1 LAST OFFPAGE TRUE
J 2
(-4800 4275);
DISPLAY 0.872340 (-4800 4275);
PAINT GREEN (-4800 4275);
DISPLAY INVISIBLE (-4800 4275);
FORCEPROP 1 LAST COMMENT_BODY TRUE
J 2
(-4450 4300);
DISPLAY 0.872340 (-4450 4300);
PAINT GREEN (-4450 4300);
DISPLAY INVISIBLE (-4450 4300);
FORCEADD OFFPAGE..2
R 2
(-4475 1500);
FORCEPROP 2 LAST $XR1 29 
J 0
(-4820 1500);
DISPLAY 0.638298 (-4820 1500);
PAINT MONO (-4820 1500);
FORCEPROP 2 LAST $XR0 192 
J 0
(-4730 1500);
DISPLAY 0.638298 (-4730 1500);
PAINT MONO (-4730 1500);
FORCEPROP 2 LAST PATH I244
J 0
(-4425 1575);
DISPLAY 1.021277 (-4425 1575);
PAINT ORANGE (-4425 1575);
DISPLAY INVISIBLE (-4425 1575);
FORCEPROP 2 LAST CDS_LIB mstr_standard
J 0
(-4475 1500);
PAINT ORANGE (-4475 1500);
DISPLAY INVISIBLE (-4475 1500);
FORCEPROP 1 LAST OFFPAGE TRUE
J 2
(-4800 1375);
DISPLAY 1.170213 (-4800 1375);
PAINT GREEN (-4800 1375);
DISPLAY INVISIBLE (-4800 1375);
FORCEPROP 1 LAST COMMENT_BODY TRUE
J 2
(-4430 1405);
DISPLAY 1.170213 (-4430 1405);
PAINT GREEN (-4430 1405);
DISPLAY INVISIBLE (-4430 1405);
FORCEADD OFFPAGE..4
R 2
(-4475 1750);
FORCEPROP 2 LAST $XR0 206 
J 0
(-4727 1750);
DISPLAY 0.638298 (-4727 1750);
PAINT MONO (-4727 1750);
FORCEPROP 2 LAST PATH I246
J 0
(-4425 1825);
DISPLAY 1.021277 (-4425 1825);
PAINT ORANGE (-4425 1825);
DISPLAY INVISIBLE (-4425 1825);
FORCEPROP 2 LAST CDS_LIB mstr_standard
J 0
(-4475 1750);
PAINT ORANGE (-4475 1750);
DISPLAY INVISIBLE (-4475 1750);
FORCEPROP 1 LAST OFFPAGE TRUE
J 2
(-4800 1625);
DISPLAY 1.170213 (-4800 1625);
PAINT GREEN (-4800 1625);
DISPLAY INVISIBLE (-4800 1625);
FORCEPROP 1 LAST COMMENT_BODY TRUE
J 2
(-4450 1650);
DISPLAY 1.170213 (-4450 1650);
PAINT GREEN (-4450 1650);
DISPLAY INVISIBLE (-4450 1650);
FORCEADD OFFPAGE..2
R 2
(-4475 1800);
FORCEPROP 2 LAST $XR0 108 
J 0
(-4730 1800);
DISPLAY 0.638298 (-4730 1800);
PAINT MONO (-4730 1800);
FORCEPROP 2 LAST PATH I248
J 0
(-4425 1875);
DISPLAY 1.021277 (-4425 1875);
PAINT ORANGE (-4425 1875);
DISPLAY INVISIBLE (-4425 1875);
FORCEPROP 2 LAST CDS_LIB mstr_standard
J 0
(-4475 1800);
PAINT ORANGE (-4475 1800);
DISPLAY INVISIBLE (-4475 1800);
FORCEPROP 1 LAST OFFPAGE TRUE
J 2
(-4800 1675);
DISPLAY 1.170213 (-4800 1675);
PAINT GREEN (-4800 1675);
DISPLAY INVISIBLE (-4800 1675);
FORCEPROP 1 LAST COMMENT_BODY TRUE
J 2
(-4430 1705);
DISPLAY 1.170213 (-4430 1705);
PAINT GREEN (-4430 1705);
DISPLAY INVISIBLE (-4430 1705);
FORCEADD OFFPAGE..2
R 2
(-4475 2150);
FORCEPROP 2 LAST $XR0 96 
J 0
(-4699 2150);
DISPLAY 0.638298 (-4699 2150);
PAINT MONO (-4699 2150);
FORCEPROP 2 LAST PATH I252
J 0
(-4425 2225);
DISPLAY 1.021277 (-4425 2225);
PAINT ORANGE (-4425 2225);
DISPLAY INVISIBLE (-4425 2225);
FORCEPROP 2 LAST CDS_LIB mstr_standard
J 0
(-4475 2150);
PAINT ORANGE (-4475 2150);
DISPLAY INVISIBLE (-4475 2150);
FORCEPROP 1 LAST OFFPAGE TRUE
J 2
(-4800 2025);
DISPLAY 1.170213 (-4800 2025);
PAINT GREEN (-4800 2025);
DISPLAY INVISIBLE (-4800 2025);
FORCEPROP 1 LAST COMMENT_BODY TRUE
J 2
(-4430 2055);
DISPLAY 1.170213 (-4430 2055);
PAINT GREEN (-4430 2055);
DISPLAY INVISIBLE (-4430 2055);
FORCEADD OFFPAGE..4
R 2
(-4475 2300);
FORCEPROP 2 LAST $XR0 201 
J 0
(-4727 2300);
DISPLAY 0.638298 (-4727 2300);
PAINT MONO (-4727 2300);
FORCEPROP 2 LAST PATH I255
J 0
(-4425 2375);
DISPLAY 1.021277 (-4425 2375);
PAINT ORANGE (-4425 2375);
DISPLAY INVISIBLE (-4425 2375);
FORCEPROP 2 LAST CDS_LIB mstr_standard
J 0
(-4475 2300);
PAINT ORANGE (-4475 2300);
DISPLAY INVISIBLE (-4475 2300);
FORCEPROP 1 LAST OFFPAGE TRUE
J 2
(-4800 2175);
DISPLAY 1.170213 (-4800 2175);
PAINT GREEN (-4800 2175);
DISPLAY INVISIBLE (-4800 2175);
FORCEPROP 1 LAST COMMENT_BODY TRUE
J 2
(-4450 2200);
DISPLAY 1.170213 (-4450 2200);
PAINT GREEN (-4450 2200);
DISPLAY INVISIBLE (-4450 2200);
FORCEADD OFFPAGE..4
R 2
(-4475 2800);
FORCEPROP 2 LAST $XR0 144 
J 0
(-4727 2800);
DISPLAY 0.638298 (-4727 2800);
PAINT MONO (-4727 2800);
FORCEPROP 2 LAST PATH I260
J 0
(-4425 2875);
DISPLAY 1.021277 (-4425 2875);
PAINT ORANGE (-4425 2875);
DISPLAY INVISIBLE (-4425 2875);
FORCEPROP 2 LAST CDS_LIB mstr_standard
J 0
(-4475 2800);
PAINT ORANGE (-4475 2800);
DISPLAY INVISIBLE (-4475 2800);
FORCEPROP 1 LAST OFFPAGE TRUE
J 2
(-4800 2675);
DISPLAY 0.872340 (-4800 2675);
PAINT GREEN (-4800 2675);
DISPLAY INVISIBLE (-4800 2675);
FORCEPROP 1 LAST COMMENT_BODY TRUE
J 2
(-4450 2700);
DISPLAY 0.872340 (-4450 2700);
PAINT GREEN (-4450 2700);
DISPLAY INVISIBLE (-4450 2700);
FORCEADD OFFPAGE..2
R 2
(-4475 2750);
FORCEPROP 2 LAST $XR0 194 
J 0
(-4730 2750);
DISPLAY 0.638298 (-4730 2750);
PAINT MONO (-4730 2750);
FORCEPROP 2 LAST PATH I261
J 0
(-4425 2825);
DISPLAY 1.021277 (-4425 2825);
PAINT ORANGE (-4425 2825);
DISPLAY INVISIBLE (-4425 2825);
FORCEPROP 2 LAST CDS_LIB mstr_standard
J 0
(-4475 2750);
PAINT ORANGE (-4475 2750);
DISPLAY INVISIBLE (-4475 2750);
FORCEPROP 1 LAST OFFPAGE TRUE
J 2
(-4800 2625);
DISPLAY 1.170213 (-4800 2625);
PAINT GREEN (-4800 2625);
DISPLAY INVISIBLE (-4800 2625);
FORCEPROP 1 LAST COMMENT_BODY TRUE
J 2
(-4430 2655);
DISPLAY 1.170213 (-4430 2655);
PAINT GREEN (-4430 2655);
DISPLAY INVISIBLE (-4430 2655);
FORCEADD OFFPAGE..4
R 2
(-4475 2950);
FORCEPROP 2 LAST $XR0 144 
J 0
(-4727 2950);
DISPLAY 0.638298 (-4727 2950);
PAINT MONO (-4727 2950);
FORCEPROP 2 LAST PATH I263
J 0
(-4425 3025);
DISPLAY 1.021277 (-4425 3025);
PAINT ORANGE (-4425 3025);
DISPLAY INVISIBLE (-4425 3025);
FORCEPROP 2 LAST CDS_LIB mstr_standard
J 0
(-4475 2950);
PAINT ORANGE (-4475 2950);
DISPLAY INVISIBLE (-4475 2950);
FORCEPROP 1 LAST OFFPAGE TRUE
J 2
(-4800 2825);
DISPLAY 1.170213 (-4800 2825);
PAINT GREEN (-4800 2825);
DISPLAY INVISIBLE (-4800 2825);
FORCEPROP 1 LAST COMMENT_BODY TRUE
J 2
(-4450 2850);
DISPLAY 1.170213 (-4450 2850);
PAINT GREEN (-4450 2850);
DISPLAY INVISIBLE (-4450 2850);
FORCEADD OFFPAGE..2
R 2
(-4475 3250);
FORCEPROP 2 LAST $XR0 194 
J 0
(-4730 3250);
DISPLAY 0.638298 (-4730 3250);
PAINT MONO (-4730 3250);
FORCEPROP 2 LAST PATH I267
J 0
(-4425 3325);
DISPLAY 1.021277 (-4425 3325);
PAINT ORANGE (-4425 3325);
DISPLAY INVISIBLE (-4425 3325);
FORCEPROP 2 LAST CDS_LIB mstr_standard
J 0
(-4475 3250);
PAINT ORANGE (-4475 3250);
DISPLAY INVISIBLE (-4475 3250);
FORCEPROP 1 LAST OFFPAGE TRUE
J 2
(-4800 3125);
DISPLAY 1.170213 (-4800 3125);
PAINT GREEN (-4800 3125);
DISPLAY INVISIBLE (-4800 3125);
FORCEPROP 1 LAST COMMENT_BODY TRUE
J 2
(-4430 3155);
DISPLAY 1.170213 (-4430 3155);
PAINT GREEN (-4430 3155);
DISPLAY INVISIBLE (-4430 3155);
FORCEADD OFFPAGE..4
R 2
(-4475 3300);
FORCEPROP 2 LAST $XR2 247 
J 0
(-4967 3300);
DISPLAY 0.638298 (-4967 3300);
PAINT MONO (-4967 3300);
FORCEPROP 2 LAST $XR1 148 
J 0
(-4847 3300);
DISPLAY 0.638298 (-4847 3300);
PAINT MONO (-4847 3300);
FORCEPROP 2 LAST $XR0 118 
J 0
(-4727 3300);
DISPLAY 0.638298 (-4727 3300);
PAINT MONO (-4727 3300);
FORCEPROP 2 LAST PATH I268
J 0
(-4425 3375);
DISPLAY 1.021277 (-4425 3375);
PAINT ORANGE (-4425 3375);
DISPLAY INVISIBLE (-4425 3375);
FORCEPROP 2 LAST CDS_LIB mstr_standard
J 0
(-4475 3300);
PAINT ORANGE (-4475 3300);
DISPLAY INVISIBLE (-4475 3300);
FORCEPROP 1 LAST OFFPAGE TRUE
J 2
(-4800 3175);
DISPLAY 1.170213 (-4800 3175);
PAINT GREEN (-4800 3175);
DISPLAY INVISIBLE (-4800 3175);
FORCEPROP 1 LAST COMMENT_BODY TRUE
J 2
(-4450 3200);
DISPLAY 1.170213 (-4450 3200);
PAINT GREEN (-4450 3200);
DISPLAY INVISIBLE (-4450 3200);
FORCEADD OFFPAGE..4
R 2
(-4475 3400);
FORCEPROP 2 LAST $XR2 248 
J 0
(-4967 3400);
DISPLAY 0.638298 (-4967 3400);
PAINT MONO (-4967 3400);
FORCEPROP 2 LAST $XR1 175 
J 0
(-4847 3400);
DISPLAY 0.638298 (-4847 3400);
PAINT MONO (-4847 3400);
FORCEPROP 2 LAST $XR0 196 
J 0
(-4727 3400);
DISPLAY 0.638298 (-4727 3400);
PAINT MONO (-4727 3400);
FORCEPROP 2 LAST PATH I269
J 0
(-4425 3475);
DISPLAY 1.021277 (-4425 3475);
PAINT ORANGE (-4425 3475);
DISPLAY INVISIBLE (-4425 3475);
FORCEPROP 2 LAST CDS_LIB mstr_standard
J 0
(-4475 3400);
PAINT ORANGE (-4475 3400);
DISPLAY INVISIBLE (-4475 3400);
FORCEPROP 1 LAST OFFPAGE TRUE
J 2
(-4800 3275);
DISPLAY 1.170213 (-4800 3275);
PAINT GREEN (-4800 3275);
DISPLAY INVISIBLE (-4800 3275);
FORCEPROP 1 LAST COMMENT_BODY TRUE
J 2
(-4450 3300);
DISPLAY 1.170213 (-4450 3300);
PAINT GREEN (-4450 3300);
DISPLAY INVISIBLE (-4450 3300);
FORCEADD OFFPAGE..2
R 2
(-4475 3450);
FORCEPROP 2 LAST $XR0 144 
J 0
(-4730 3450);
DISPLAY 0.638298 (-4730 3450);
PAINT MONO (-4730 3450);
FORCEPROP 2 LAST PATH I270
J 0
(-4425 3525);
DISPLAY 1.021277 (-4425 3525);
PAINT ORANGE (-4425 3525);
DISPLAY INVISIBLE (-4425 3525);
FORCEPROP 2 LAST CDS_LIB mstr_standard
J 0
(-4475 3450);
PAINT ORANGE (-4475 3450);
DISPLAY INVISIBLE (-4475 3450);
FORCEPROP 1 LAST OFFPAGE TRUE
J 2
(-4800 3325);
DISPLAY 1.170213 (-4800 3325);
PAINT GREEN (-4800 3325);
DISPLAY INVISIBLE (-4800 3325);
FORCEPROP 1 LAST COMMENT_BODY TRUE
J 2
(-4430 3355);
DISPLAY 1.170213 (-4430 3355);
PAINT GREEN (-4430 3355);
DISPLAY INVISIBLE (-4430 3355);
FORCEADD OFFPAGE..4
R 2
(-4475 3500);
FORCEPROP 2 LAST $XR1 113 
J 0
(-4816 3500);
DISPLAY 0.638298 (-4816 3500);
PAINT MONO (-4816 3500);
FORCEPROP 2 LAST $XR0 21 
J 0
(-4696 3500);
DISPLAY 0.638298 (-4696 3500);
PAINT MONO (-4696 3500);
FORCEPROP 2 LAST PATH I271
J 0
(-4425 3575);
DISPLAY 1.021277 (-4425 3575);
PAINT ORANGE (-4425 3575);
DISPLAY INVISIBLE (-4425 3575);
FORCEPROP 2 LAST CDS_LIB mstr_standard
J 0
(-4475 3500);
PAINT ORANGE (-4475 3500);
DISPLAY INVISIBLE (-4475 3500);
FORCEPROP 1 LAST OFFPAGE TRUE
J 2
(-4800 3375);
DISPLAY 1.170213 (-4800 3375);
PAINT GREEN (-4800 3375);
DISPLAY INVISIBLE (-4800 3375);
FORCEPROP 1 LAST COMMENT_BODY TRUE
J 2
(-4450 3400);
DISPLAY 1.170213 (-4450 3400);
PAINT GREEN (-4450 3400);
DISPLAY INVISIBLE (-4450 3400);
FORCEADD OFFPAGE..3
R 2
(-4475 3650);
FORCEPROP 2 LAST $XR0 190 
J 0
(-4755 3650);
DISPLAY 0.638298 (-4755 3650);
PAINT MONO (-4755 3650);
FORCEPROP 2 LAST PATH I272
J 0
(-4425 3725);
DISPLAY 1.021277 (-4425 3725);
PAINT ORANGE (-4425 3725);
DISPLAY INVISIBLE (-4425 3725);
FORCEPROP 2 LAST CDS_LIB mstr_standard
J 0
(-4475 3650);
PAINT ORANGE (-4475 3650);
DISPLAY INVISIBLE (-4475 3650);
FORCEPROP 1 LAST OFFPAGE TRUE
J 2
(-4800 3525);
DISPLAY 0.872340 (-4800 3525);
PAINT GREEN (-4800 3525);
DISPLAY INVISIBLE (-4800 3525);
FORCEPROP 1 LAST COMMENT_BODY TRUE
J 2
(-4425 3550);
DISPLAY 0.872340 (-4425 3550);
PAINT GREEN (-4425 3550);
DISPLAY INVISIBLE (-4425 3550);
FORCEADD OFFPAGE..4
R 2
(-4475 3550);
FORCEPROP 2 LAST $XR0 21 
J 0
(-4696 3550);
DISPLAY 0.638298 (-4696 3550);
PAINT MONO (-4696 3550);
FORCEPROP 2 LAST PATH I273
J 0
(-4425 3625);
DISPLAY 1.021277 (-4425 3625);
PAINT ORANGE (-4425 3625);
DISPLAY INVISIBLE (-4425 3625);
FORCEPROP 2 LAST CDS_LIB mstr_standard
J 0
(-4475 3550);
PAINT ORANGE (-4475 3550);
DISPLAY INVISIBLE (-4475 3550);
FORCEPROP 1 LAST OFFPAGE TRUE
J 2
(-4800 3425);
DISPLAY 1.170213 (-4800 3425);
PAINT GREEN (-4800 3425);
DISPLAY INVISIBLE (-4800 3425);
FORCEPROP 1 LAST COMMENT_BODY TRUE
J 2
(-4450 3450);
DISPLAY 1.170213 (-4450 3450);
PAINT GREEN (-4450 3450);
DISPLAY INVISIBLE (-4450 3450);
FORCEADD OFFPAGE..4
R 2
(-4475 3750);
FORCEPROP 2 LAST $XR0 21 
J 0
(-4696 3750);
DISPLAY 0.638298 (-4696 3750);
PAINT MONO (-4696 3750);
FORCEPROP 2 LAST PATH I275
J 0
(-4425 3825);
DISPLAY 1.021277 (-4425 3825);
PAINT ORANGE (-4425 3825);
DISPLAY INVISIBLE (-4425 3825);
FORCEPROP 2 LAST CDS_LIB mstr_standard
J 0
(-4475 3750);
PAINT ORANGE (-4475 3750);
DISPLAY INVISIBLE (-4475 3750);
FORCEPROP 1 LAST OFFPAGE TRUE
J 2
(-4800 3625);
DISPLAY 1.170213 (-4800 3625);
PAINT GREEN (-4800 3625);
DISPLAY INVISIBLE (-4800 3625);
FORCEPROP 1 LAST COMMENT_BODY TRUE
J 2
(-4450 3650);
DISPLAY 1.170213 (-4450 3650);
PAINT GREEN (-4450 3650);
DISPLAY INVISIBLE (-4450 3650);
FORCEADD OFFPAGE..4
R 2
(-4475 3800);
FORCEPROP 2 LAST $XR0 21 
J 0
(-4696 3800);
DISPLAY 0.638298 (-4696 3800);
PAINT MONO (-4696 3800);
FORCEPROP 2 LAST PATH I276
J 0
(-4425 3875);
DISPLAY 1.021277 (-4425 3875);
PAINT ORANGE (-4425 3875);
DISPLAY INVISIBLE (-4425 3875);
FORCEPROP 2 LAST CDS_LIB mstr_standard
J 0
(-4475 3800);
PAINT ORANGE (-4475 3800);
DISPLAY INVISIBLE (-4475 3800);
FORCEPROP 1 LAST OFFPAGE TRUE
J 2
(-4800 3675);
DISPLAY 1.170213 (-4800 3675);
PAINT GREEN (-4800 3675);
DISPLAY INVISIBLE (-4800 3675);
FORCEPROP 1 LAST COMMENT_BODY TRUE
J 2
(-4450 3700);
DISPLAY 1.170213 (-4450 3700);
PAINT GREEN (-4450 3700);
DISPLAY INVISIBLE (-4450 3700);
FORCEADD OFFPAGE..4
R 2
(-4475 3900);
FORCEPROP 2 LAST $XR2 145 
J 0
(-4967 3900);
DISPLAY 0.638298 (-4967 3900);
PAINT MONO (-4967 3900);
FORCEPROP 2 LAST $XR1 119 
J 0
(-4847 3900);
DISPLAY 0.638298 (-4847 3900);
PAINT MONO (-4847 3900);
FORCEPROP 2 LAST $XR0 175 
J 0
(-4727 3900);
DISPLAY 0.638298 (-4727 3900);
PAINT MONO (-4727 3900);
FORCEPROP 2 LAST PATH I277
J 0
(-4425 3975);
DISPLAY 1.021277 (-4425 3975);
PAINT ORANGE (-4425 3975);
DISPLAY INVISIBLE (-4425 3975);
FORCEPROP 2 LAST CDS_LIB mstr_standard
J 2
(-4475 3900);
PAINT ORANGE (-4475 3900);
DISPLAY INVISIBLE (-4475 3900);
FORCEPROP 1 LAST OFFPAGE TRUE
J 2
(-4800 3775);
DISPLAY 0.872340 (-4800 3775);
PAINT GREEN (-4800 3775);
DISPLAY INVISIBLE (-4800 3775);
FORCEPROP 1 LAST COMMENT_BODY TRUE
J 2
(-4450 3800);
DISPLAY 0.872340 (-4450 3800);
PAINT GREEN (-4450 3800);
DISPLAY INVISIBLE (-4450 3800);
FORCEADD OFFPAGE..4
R 2
(-4475 4050);
FORCEPROP 2 LAST $XR0 101 
J 0
(-4727 4050);
DISPLAY 0.638298 (-4727 4050);
PAINT MONO (-4727 4050);
FORCEPROP 2 LAST PATH I279
J 0
(-4425 4125);
DISPLAY 1.021277 (-4425 4125);
PAINT ORANGE (-4425 4125);
DISPLAY INVISIBLE (-4425 4125);
FORCEPROP 2 LAST CDS_LIB mstr_standard
J 0
(-4475 4050);
PAINT ORANGE (-4475 4050);
DISPLAY INVISIBLE (-4475 4050);
FORCEPROP 1 LAST OFFPAGE TRUE
J 2
(-4800 3925);
DISPLAY 1.170213 (-4800 3925);
PAINT GREEN (-4800 3925);
DISPLAY INVISIBLE (-4800 3925);
FORCEPROP 1 LAST COMMENT_BODY TRUE
J 2
(-4450 3950);
DISPLAY 1.170213 (-4450 3950);
PAINT GREEN (-4450 3950);
DISPLAY INVISIBLE (-4450 3950);
FORCEADD OFFPAGE..4
R 2
(-4475 4000);
FORCEPROP 2 LAST $XR0 21 
J 0
(-4696 4000);
DISPLAY 0.638298 (-4696 4000);
PAINT MONO (-4696 4000);
FORCEPROP 2 LAST PATH I280
J 0
(-4425 4075);
DISPLAY 1.021277 (-4425 4075);
PAINT ORANGE (-4425 4075);
DISPLAY INVISIBLE (-4425 4075);
FORCEPROP 2 LAST CDS_LIB mstr_standard
J 0
(-4475 4000);
PAINT ORANGE (-4475 4000);
DISPLAY INVISIBLE (-4475 4000);
FORCEPROP 1 LAST OFFPAGE TRUE
J 2
(-4800 3875);
DISPLAY 1.170213 (-4800 3875);
PAINT GREEN (-4800 3875);
DISPLAY INVISIBLE (-4800 3875);
FORCEPROP 1 LAST COMMENT_BODY TRUE
J 2
(-4450 3900);
DISPLAY 1.170213 (-4450 3900);
PAINT GREEN (-4450 3900);
DISPLAY INVISIBLE (-4450 3900);
FORCEADD OFFPAGE..2
R 2
(-4475 4300);
FORCEPROP 2 LAST $XR0 119 
J 0
(-4730 4300);
DISPLAY 0.638298 (-4730 4300);
PAINT MONO (-4730 4300);
FORCEPROP 2 LAST PATH I284
J 0
(-4425 4375);
DISPLAY 1.021277 (-4425 4375);
PAINT ORANGE (-4425 4375);
DISPLAY INVISIBLE (-4425 4375);
FORCEPROP 2 LAST CDS_LIB mstr_standard
J 2
(-4475 4300);
PAINT ORANGE (-4475 4300);
DISPLAY INVISIBLE (-4475 4300);
FORCEPROP 1 LAST OFFPAGE TRUE
J 2
(-4800 4175);
DISPLAY 1.170213 (-4800 4175);
PAINT GREEN (-4800 4175);
DISPLAY INVISIBLE (-4800 4175);
FORCEPROP 1 LAST COMMENT_BODY TRUE
J 2
(-4430 4205);
DISPLAY 1.170213 (-4430 4205);
PAINT GREEN (-4430 4205);
DISPLAY INVISIBLE (-4430 4205);
FORCEADD OFFPAGE..2
R 2
(-4475 4450);
FORCEPROP 2 LAST $XR0 121 
J 0
(-4730 4450);
DISPLAY 0.638298 (-4730 4450);
PAINT MONO (-4730 4450);
FORCEPROP 2 LAST PATH I285
J 0
(-4425 4525);
DISPLAY 1.021277 (-4425 4525);
PAINT ORANGE (-4425 4525);
DISPLAY INVISIBLE (-4425 4525);
FORCEPROP 2 LAST CDS_LIB mstr_standard
J 0
(-4475 4450);
PAINT ORANGE (-4475 4450);
DISPLAY INVISIBLE (-4475 4450);
FORCEPROP 1 LAST OFFPAGE TRUE
J 2
(-4800 4325);
DISPLAY 1.170213 (-4800 4325);
PAINT GREEN (-4800 4325);
DISPLAY INVISIBLE (-4800 4325);
FORCEPROP 1 LAST COMMENT_BODY TRUE
J 2
(-4430 4355);
DISPLAY 1.170213 (-4430 4355);
PAINT GREEN (-4430 4355);
DISPLAY INVISIBLE (-4430 4355);
FORCEADD OFFPAGE..4
R 2
(-4475 3950);
FORCEPROP 2 LAST $XR0 192 
J 0
(-4727 3950);
DISPLAY 0.638298 (-4727 3950);
PAINT MONO (-4727 3950);
FORCEPROP 2 LAST PATH I298
J 0
(-4425 4025);
DISPLAY 1.021277 (-4425 4025);
PAINT ORANGE (-4425 4025);
DISPLAY INVISIBLE (-4425 4025);
FORCEPROP 2 LAST CDS_LIB mstr_standard
J 0
(-4475 3950);
PAINT MONO (-4475 3950);
DISPLAY INVISIBLE (-4475 3950);
FORCEPROP 1 LAST OFFPAGE TRUE
J 2
(-4800 3825);
DISPLAY 1.170213 (-4800 3825);
PAINT GREEN (-4800 3825);
DISPLAY INVISIBLE (-4800 3825);
FORCEPROP 1 LAST COMMENT_BODY TRUE
J 2
(-4450 3850);
DISPLAY 1.170213 (-4450 3850);
PAINT GREEN (-4450 3850);
DISPLAY INVISIBLE (-4450 3850);
FORCEADD OFFPAGE..4
R 2
(-4475 3150);
FORCEPROP 2 LAST $XR0 196 
J 0
(-4727 3150);
DISPLAY 0.638298 (-4727 3150);
PAINT MONO (-4727 3150);
FORCEPROP 2 LAST PATH I299
J 0
(-4425 3225);
DISPLAY 1.021277 (-4425 3225);
PAINT ORANGE (-4425 3225);
DISPLAY INVISIBLE (-4425 3225);
FORCEPROP 2 LAST CDS_LIB mstr_standard
J 0
(-4475 3150);
PAINT MONO (-4475 3150);
DISPLAY INVISIBLE (-4475 3150);
FORCEPROP 1 LAST OFFPAGE TRUE
J 2
(-4800 3025);
DISPLAY 1.170213 (-4800 3025);
PAINT GREEN (-4800 3025);
DISPLAY INVISIBLE (-4800 3025);
FORCEPROP 1 LAST COMMENT_BODY TRUE
J 2
(-4450 3050);
DISPLAY 1.170213 (-4450 3050);
PAINT GREEN (-4450 3050);
DISPLAY INVISIBLE (-4450 3050);
FORCEADD OFFPAGE..2
R 2
(-4475 4200);
FORCEPROP 2 LAST $XR0 187 
J 0
(-4730 4200);
DISPLAY 0.638298 (-4730 4200);
PAINT MONO (-4730 4200);
FORCEPROP 2 LAST PATH I301
J 0
(-4425 4275);
DISPLAY 1.021277 (-4425 4275);
PAINT ORANGE (-4425 4275);
DISPLAY INVISIBLE (-4425 4275);
FORCEPROP 2 LAST CDS_LIB mstr_standard
J 0
(-4475 4200);
PAINT MONO (-4475 4200);
DISPLAY INVISIBLE (-4475 4200);
FORCEPROP 1 LAST OFFPAGE TRUE
J 2
(-4800 4075);
DISPLAY 1.170213 (-4800 4075);
PAINT GREEN (-4800 4075);
DISPLAY INVISIBLE (-4800 4075);
FORCEPROP 1 LAST COMMENT_BODY TRUE
J 2
(-4430 4105);
DISPLAY 1.170213 (-4430 4105);
PAINT GREEN (-4430 4105);
DISPLAY INVISIBLE (-4430 4105);
FORCEADD OFFPAGE..2
R 2
(-4475 3050);
FORCEPROP 2 LAST $XR0 187 
J 0
(-4730 3050);
DISPLAY 0.638298 (-4730 3050);
PAINT MONO (-4730 3050);
FORCEPROP 2 LAST PATH I302
J 0
(-4425 3125);
DISPLAY 1.021277 (-4425 3125);
PAINT ORANGE (-4425 3125);
DISPLAY INVISIBLE (-4425 3125);
FORCEPROP 2 LAST CDS_LIB mstr_standard
J 0
(-4475 3050);
PAINT MONO (-4475 3050);
DISPLAY INVISIBLE (-4475 3050);
FORCEPROP 1 LAST OFFPAGE TRUE
J 2
(-4800 2925);
DISPLAY 1.170213 (-4800 2925);
PAINT GREEN (-4800 2925);
DISPLAY INVISIBLE (-4800 2925);
FORCEPROP 1 LAST COMMENT_BODY TRUE
J 2
(-4430 2955);
DISPLAY 1.170213 (-4430 2955);
PAINT GREEN (-4430 2955);
DISPLAY INVISIBLE (-4430 2955);
FORCEADD OFFPAGE..2
R 2
(-4475 3000);
FORCEPROP 2 LAST $XR0 187 
J 0
(-4730 3000);
DISPLAY 0.638298 (-4730 3000);
PAINT MONO (-4730 3000);
FORCEPROP 2 LAST PATH I303
J 0
(-4425 3075);
DISPLAY 1.021277 (-4425 3075);
PAINT ORANGE (-4425 3075);
DISPLAY INVISIBLE (-4425 3075);
FORCEPROP 2 LAST CDS_LIB mstr_standard
J 0
(-4475 3000);
PAINT MONO (-4475 3000);
DISPLAY INVISIBLE (-4475 3000);
FORCEPROP 1 LAST OFFPAGE TRUE
J 2
(-4800 2875);
DISPLAY 1.170213 (-4800 2875);
PAINT GREEN (-4800 2875);
DISPLAY INVISIBLE (-4800 2875);
FORCEPROP 1 LAST COMMENT_BODY TRUE
J 2
(-4430 2905);
DISPLAY 1.170213 (-4430 2905);
PAINT GREEN (-4430 2905);
DISPLAY INVISIBLE (-4430 2905);
FORCEADD OFFPAGE..2
(300 2050);
FORCEPROP 2 LAST $XR2 158 
J 0
(729 2050);
DISPLAY 0.638298 (729 2050);
PAINT MONO (729 2050);
FORCEPROP 2 LAST $XR1 144 
J 0
(609 2050);
DISPLAY 0.638298 (609 2050);
PAINT MONO (609 2050);
FORCEPROP 2 LAST $XR0 120 
J 0
(489 2050);
DISPLAY 0.638298 (489 2050);
PAINT MONO (489 2050);
FORCEPROP 2 LAST CDS_LIB mstr_standard
J 0
(300 2050);
PAINT MONO (300 2050);
DISPLAY INVISIBLE (300 2050);
FORCEPROP 2 LAST PATH I304
J 0
(475 2125);
DISPLAY 1.021277 (475 2125);
PAINT ORANGE (475 2125);
DISPLAY INVISIBLE (475 2125);
FORCEPROP 1 LAST OFFPAGE TRUE
J 0
(625 1925);
DISPLAY 1.170213 (625 1925);
PAINT GREEN (625 1925);
DISPLAY INVISIBLE (625 1925);
FORCEPROP 1 LAST COMMENT_BODY TRUE
J 0
(255 1955);
DISPLAY 1.170213 (255 1955);
PAINT GREEN (255 1955);
DISPLAY INVISIBLE (255 1955);
FORCEADD OFFPAGE..2
(300 2600);
FORCEPROP 2 LAST $XR2 158 
J 0
(729 2600);
DISPLAY 0.638298 (729 2600);
PAINT MONO (729 2600);
FORCEPROP 2 LAST $XR1 144 
J 0
(609 2600);
DISPLAY 0.638298 (609 2600);
PAINT MONO (609 2600);
FORCEPROP 2 LAST $XR0 120 
J 0
(489 2600);
DISPLAY 0.638298 (489 2600);
PAINT MONO (489 2600);
FORCEPROP 2 LAST CDS_LIB mstr_standard
J 0
(300 2600);
PAINT MONO (300 2600);
DISPLAY INVISIBLE (300 2600);
FORCEPROP 2 LAST PATH I305
J 0
(475 2675);
DISPLAY 1.021277 (475 2675);
PAINT ORANGE (475 2675);
DISPLAY INVISIBLE (475 2675);
FORCEPROP 1 LAST OFFPAGE TRUE
J 0
(625 2475);
DISPLAY 1.170213 (625 2475);
PAINT GREEN (625 2475);
DISPLAY INVISIBLE (625 2475);
FORCEPROP 1 LAST COMMENT_BODY TRUE
J 0
(255 2505);
DISPLAY 1.170213 (255 2505);
PAINT GREEN (255 2505);
DISPLAY INVISIBLE (255 2505);
FORCEADD OFFPAGE..4
(300 3000);
FORCEPROP 2 LAST $XR1 120 
J 0
(606 3000);
DISPLAY 0.638298 (606 3000);
PAINT MONO (606 3000);
FORCEPROP 2 LAST $XR0 135 
J 0
(486 3000);
DISPLAY 0.638298 (486 3000);
PAINT MONO (486 3000);
FORCEPROP 2 LAST CDS_LIB mstr_standard
J 0
(300 3000);
PAINT MONO (300 3000);
DISPLAY INVISIBLE (300 3000);
FORCEPROP 2 LAST PATH I306
J 0
(475 3075);
DISPLAY 1.021277 (475 3075);
PAINT ORANGE (475 3075);
DISPLAY INVISIBLE (475 3075);
FORCEPROP 1 LAST OFFPAGE TRUE
J 0
(625 2875);
DISPLAY 1.170213 (625 2875);
PAINT GREEN (625 2875);
DISPLAY INVISIBLE (625 2875);
FORCEPROP 1 LAST COMMENT_BODY TRUE
J 0
(275 2900);
DISPLAY 1.170213 (275 2900);
PAINT GREEN (275 2900);
DISPLAY INVISIBLE (275 2900);
FORCEADD OFFPAGE..4
R 2
(-4475 1450);
FORCEPROP 2 LAST $XR2 157 
J 0
(-4967 1450);
DISPLAY 0.638298 (-4967 1450);
PAINT MONO (-4967 1450);
FORCEPROP 2 LAST $XR1 146 
J 0
(-4847 1450);
DISPLAY 0.638298 (-4847 1450);
PAINT MONO (-4847 1450);
FORCEPROP 2 LAST $XR0 119 
J 0
(-4727 1450);
DISPLAY 0.638298 (-4727 1450);
PAINT MONO (-4727 1450);
FORCEPROP 2 LAST PATH I307
J 0
(-4425 1525);
DISPLAY 1.021277 (-4425 1525);
PAINT ORANGE (-4425 1525);
DISPLAY INVISIBLE (-4425 1525);
FORCEPROP 2 LAST CDS_LIB mstr_standard
J 0
(-4475 1450);
PAINT MONO (-4475 1450);
DISPLAY INVISIBLE (-4475 1450);
FORCEPROP 1 LAST OFFPAGE TRUE
J 2
(-4800 1325);
DISPLAY 1.170213 (-4800 1325);
PAINT GREEN (-4800 1325);
DISPLAY INVISIBLE (-4800 1325);
FORCEPROP 1 LAST COMMENT_BODY TRUE
J 2
(-4450 1350);
DISPLAY 1.170213 (-4450 1350);
PAINT GREEN (-4450 1350);
DISPLAY INVISIBLE (-4450 1350);
FORCEADD OFFPAGE..2
(300 3050);
FORCEPROP 2 LAST $XR0 104 
J 0
(489 3050);
DISPLAY 0.638298 (489 3050);
PAINT MONO (489 3050);
FORCEPROP 2 LAST CDS_LIB mstr_standard
J 0
(300 3050);
PAINT MONO (300 3050);
DISPLAY INVISIBLE (300 3050);
FORCEPROP 2 LAST PATH I308
J 0
(475 3125);
DISPLAY 1.021277 (475 3125);
PAINT ORANGE (475 3125);
DISPLAY INVISIBLE (475 3125);
FORCEPROP 1 LAST OFFPAGE TRUE
J 0
(625 2925);
DISPLAY 1.170213 (625 2925);
PAINT GREEN (625 2925);
DISPLAY INVISIBLE (625 2925);
FORCEPROP 1 LAST COMMENT_BODY TRUE
J 0
(255 2955);
DISPLAY 1.170213 (255 2955);
PAINT GREEN (255 2955);
DISPLAY INVISIBLE (255 2955);
FORCEADD OFFPAGE..2
(300 2550);
FORCEPROP 2 LAST $XR0 104 
J 0
(489 2550);
DISPLAY 0.638298 (489 2550);
PAINT MONO (489 2550);
FORCEPROP 2 LAST CDS_LIB mstr_standard
J 0
(300 2550);
PAINT MONO (300 2550);
DISPLAY INVISIBLE (300 2550);
FORCEPROP 2 LAST PATH I309
J 0
(475 2625);
DISPLAY 1.021277 (475 2625);
PAINT ORANGE (475 2625);
DISPLAY INVISIBLE (475 2625);
FORCEPROP 1 LAST OFFPAGE TRUE
J 0
(625 2425);
DISPLAY 1.170213 (625 2425);
PAINT GREEN (625 2425);
DISPLAY INVISIBLE (625 2425);
FORCEPROP 1 LAST COMMENT_BODY TRUE
J 0
(255 2455);
DISPLAY 1.170213 (255 2455);
PAINT GREEN (255 2455);
DISPLAY INVISIBLE (255 2455);
FORCEADD OFFPAGE..4
R 2
(-4475 3200);
FORCEPROP 2 LAST $XR3 144 
J 0
(-5087 3200);
DISPLAY 0.638298 (-5087 3200);
PAINT MONO (-5087 3200);
FORCEPROP 2 LAST $XR2 120 
J 0
(-4967 3200);
DISPLAY 0.638298 (-4967 3200);
PAINT MONO (-4967 3200);
FORCEPROP 2 LAST $XR1 181 
J 0
(-4847 3200);
DISPLAY 0.638298 (-4847 3200);
PAINT MONO (-4847 3200);
FORCEPROP 2 LAST $XR0 157 
J 0
(-4727 3200);
DISPLAY 0.638298 (-4727 3200);
PAINT MONO (-4727 3200);
FORCEPROP 2 LAST PATH I312
J 0
(-4425 3275);
DISPLAY 1.021277 (-4425 3275);
PAINT ORANGE (-4425 3275);
DISPLAY INVISIBLE (-4425 3275);
FORCEPROP 2 LAST CDS_LIB mstr_standard
J 0
(-4475 3200);
PAINT MONO (-4475 3200);
DISPLAY INVISIBLE (-4475 3200);
FORCEPROP 1 LAST OFFPAGE TRUE
J 2
(-4800 3075);
DISPLAY 1.170213 (-4800 3075);
PAINT GREEN (-4800 3075);
DISPLAY INVISIBLE (-4800 3075);
FORCEPROP 1 LAST COMMENT_BODY TRUE
J 2
(-4450 3100);
DISPLAY 1.170213 (-4450 3100);
PAINT GREEN (-4450 3100);
DISPLAY INVISIBLE (-4450 3100);
FORCEADD OFFPAGE..4
(300 2700);
FORCEPROP 2 LAST $XR2 157 
J 0
(726 2700);
DISPLAY 0.638298 (726 2700);
PAINT MONO (726 2700);
FORCEPROP 2 LAST $XR1 145 
J 0
(606 2700);
DISPLAY 0.638298 (606 2700);
PAINT MONO (606 2700);
FORCEPROP 2 LAST $XR0 119 
J 0
(486 2700);
DISPLAY 0.638298 (486 2700);
PAINT MONO (486 2700);
FORCEPROP 2 LAST CDS_LIB mstr_standard
J 0
(300 2700);
PAINT MONO (300 2700);
DISPLAY INVISIBLE (300 2700);
FORCEPROP 2 LAST PATH I313
J 0
(475 2775);
DISPLAY 1.021277 (475 2775);
PAINT ORANGE (475 2775);
DISPLAY INVISIBLE (475 2775);
FORCEPROP 1 LAST OFFPAGE TRUE
J 0
(625 2575);
DISPLAY 1.170213 (625 2575);
PAINT GREEN (625 2575);
DISPLAY INVISIBLE (625 2575);
FORCEPROP 1 LAST COMMENT_BODY TRUE
J 0
(275 2600);
DISPLAY 1.170213 (275 2600);
PAINT GREEN (275 2600);
DISPLAY INVISIBLE (275 2600);
FORCEADD OFFPAGE..4
(300 2450);
FORCEPROP 2 LAST $XR2 145 
J 0
(726 2450);
DISPLAY 0.638298 (726 2450);
PAINT MONO (726 2450);
FORCEPROP 2 LAST $XR1 120 
J 0
(606 2450);
DISPLAY 0.638298 (606 2450);
PAINT MONO (606 2450);
FORCEPROP 2 LAST $XR0 168 
J 0
(486 2450);
DISPLAY 0.638298 (486 2450);
PAINT MONO (486 2450);
FORCEPROP 2 LAST CDS_LIB mstr_standard
J 0
(300 2450);
PAINT ORANGE (300 2450);
DISPLAY INVISIBLE (300 2450);
FORCEPROP 2 LAST PATH I314
J 0
(475 2525);
DISPLAY 1.021277 (475 2525);
PAINT ORANGE (475 2525);
DISPLAY INVISIBLE (475 2525);
FORCEPROP 1 LAST OFFPAGE TRUE
J 0
(625 2325);
DISPLAY 1.170213 (625 2325);
PAINT GREEN (625 2325);
DISPLAY INVISIBLE (625 2325);
FORCEPROP 1 LAST COMMENT_BODY TRUE
J 0
(275 2350);
DISPLAY 1.170213 (275 2350);
PAINT GREEN (275 2350);
DISPLAY INVISIBLE (275 2350);
FORCEADD OFFPAGE..2
(300 3100);
FORCEPROP 2 LAST $XR0 155 
J 0
(489 3100);
DISPLAY 0.638298 (489 3100);
PAINT MONO (489 3100);
FORCEPROP 2 LAST CDS_LIB mstr_standard
J 0
(300 3100);
PAINT ORANGE (300 3100);
DISPLAY INVISIBLE (300 3100);
FORCEPROP 2 LAST PATH I317
J 0
(475 3175);
DISPLAY 1.021277 (475 3175);
PAINT ORANGE (475 3175);
DISPLAY INVISIBLE (475 3175);
FORCEPROP 1 LAST OFFPAGE TRUE
J 0
(625 2975);
DISPLAY 1.170213 (625 2975);
PAINT GREEN (625 2975);
DISPLAY INVISIBLE (625 2975);
FORCEPROP 1 LAST COMMENT_BODY TRUE
J 0
(255 3005);
DISPLAY 1.170213 (255 3005);
PAINT GREEN (255 3005);
DISPLAY INVISIBLE (255 3005);
FORCEADD OFFPAGE..4
(300 2500);
FORCEPROP 2 LAST $XR0 135 
J 0
(486 2500);
DISPLAY 0.638298 (486 2500);
PAINT MONO (486 2500);
FORCEPROP 2 LAST CDS_LIB mstr_standard
J 0
(300 2500);
PAINT ORANGE (300 2500);
DISPLAY INVISIBLE (300 2500);
FORCEPROP 2 LAST PATH I318
J 0
(475 2575);
DISPLAY 1.021277 (475 2575);
PAINT ORANGE (475 2575);
DISPLAY INVISIBLE (475 2575);
FORCEPROP 1 LAST OFFPAGE TRUE
J 0
(625 2375);
DISPLAY 1.170213 (625 2375);
PAINT GREEN (625 2375);
DISPLAY INVISIBLE (625 2375);
FORCEPROP 1 LAST COMMENT_BODY TRUE
J 0
(275 2400);
DISPLAY 1.170213 (275 2400);
PAINT GREEN (275 2400);
DISPLAY INVISIBLE (275 2400);
FORCEADD OFFPAGE..4
(300 3250);
FORCEPROP 2 LAST $XR1 118 
J 0
(606 3250);
DISPLAY 0.638298 (606 3250);
PAINT MONO (606 3250);
FORCEPROP 2 LAST $XR0 211 
J 0
(486 3250);
DISPLAY 0.638298 (486 3250);
PAINT MONO (486 3250);
FORCEPROP 2 LAST CDS_LIB mstr_standard
J 0
(300 3250);
PAINT ORANGE (300 3250);
DISPLAY INVISIBLE (300 3250);
FORCEPROP 2 LAST PATH I319
J 0
(475 3325);
DISPLAY 1.021277 (475 3325);
PAINT ORANGE (475 3325);
DISPLAY INVISIBLE (475 3325);
FORCEPROP 1 LAST OFFPAGE TRUE
J 0
(625 3125);
DISPLAY 1.170213 (625 3125);
PAINT GREEN (625 3125);
DISPLAY INVISIBLE (625 3125);
FORCEPROP 1 LAST COMMENT_BODY TRUE
J 0
(275 3150);
DISPLAY 1.170213 (275 3150);
PAINT GREEN (275 3150);
DISPLAY INVISIBLE (275 3150);
FORCEADD OFFPAGE..4
R 2
(-4475 1550);
FORCEPROP 2 LAST $XR0 233 
J 0
(-4727 1550);
DISPLAY 0.638298 (-4727 1550);
PAINT MONO (-4727 1550);
FORCEPROP 2 LAST PATH I320
J 0
(-4425 1625);
DISPLAY 1.021277 (-4425 1625);
PAINT ORANGE (-4425 1625);
DISPLAY INVISIBLE (-4425 1625);
FORCEPROP 2 LAST CDS_LIB mstr_standard
J 0
(-4475 1550);
PAINT ORANGE (-4475 1550);
DISPLAY INVISIBLE (-4475 1550);
FORCEPROP 1 LAST OFFPAGE TRUE
J 2
(-4800 1425);
DISPLAY 1.170213 (-4800 1425);
PAINT GREEN (-4800 1425);
DISPLAY INVISIBLE (-4800 1425);
FORCEPROP 1 LAST COMMENT_BODY TRUE
J 2
(-4450 1450);
DISPLAY 1.170213 (-4450 1450);
PAINT GREEN (-4450 1450);
DISPLAY INVISIBLE (-4450 1450);
FORCEADD OFFPAGE..4
R 2
(-4475 1700);
FORCEPROP 2 LAST $XR0 234 
J 0
(-4727 1700);
DISPLAY 0.638298 (-4727 1700);
PAINT MONO (-4727 1700);
FORCEPROP 2 LAST PATH I321
J 0
(-4425 1775);
DISPLAY 1.021277 (-4425 1775);
PAINT ORANGE (-4425 1775);
DISPLAY INVISIBLE (-4425 1775);
FORCEPROP 2 LAST CDS_LIB mstr_standard
J 0
(-4475 1700);
PAINT ORANGE (-4475 1700);
DISPLAY INVISIBLE (-4475 1700);
FORCEPROP 1 LAST OFFPAGE TRUE
J 2
(-4800 1575);
DISPLAY 1.170213 (-4800 1575);
PAINT GREEN (-4800 1575);
DISPLAY INVISIBLE (-4800 1575);
FORCEPROP 1 LAST COMMENT_BODY TRUE
J 2
(-4450 1600);
DISPLAY 1.170213 (-4450 1600);
PAINT GREEN (-4450 1600);
DISPLAY INVISIBLE (-4450 1600);
FORCEADD OFFPAGE..4
(300 3500);
FORCEPROP 2 LAST $XR1 91 
J 0
(606 3500);
DISPLAY 0.638298 (606 3500);
PAINT MONO (606 3500);
FORCEPROP 2 LAST $XR0 231 
J 0
(486 3500);
DISPLAY 0.638298 (486 3500);
PAINT MONO (486 3500);
FORCEPROP 2 LAST CDS_LIB mstr_standard
J 0
(300 3500);
PAINT ORANGE (300 3500);
DISPLAY INVISIBLE (300 3500);
FORCEPROP 2 LAST PATH I322
J 0
(475 3575);
DISPLAY 1.021277 (475 3575);
PAINT ORANGE (475 3575);
DISPLAY INVISIBLE (475 3575);
FORCEPROP 1 LAST OFFPAGE TRUE
J 0
(625 3375);
DISPLAY 1.170213 (625 3375);
PAINT GREEN (625 3375);
DISPLAY INVISIBLE (625 3375);
FORCEPROP 1 LAST COMMENT_BODY TRUE
J 0
(275 3400);
DISPLAY 1.170213 (275 3400);
PAINT GREEN (275 3400);
DISPLAY INVISIBLE (275 3400);
FORCEADD OFFPAGE..4
(300 4000);
FORCEPROP 2 LAST $XR2 157 
J 0
(726 4000);
DISPLAY 0.638298 (726 4000);
PAINT MONO (726 4000);
FORCEPROP 2 LAST $XR1 147 
J 0
(606 4000);
DISPLAY 0.638298 (606 4000);
PAINT MONO (606 4000);
FORCEPROP 2 LAST $XR0 118 
J 0
(486 4000);
DISPLAY 0.638298 (486 4000);
PAINT MONO (486 4000);
FORCEPROP 2 LAST CDS_LIB mstr_standard
J 0
(300 4000);
PAINT ORANGE (300 4000);
DISPLAY INVISIBLE (300 4000);
FORCEPROP 2 LAST PATH I323
J 0
(475 4075);
DISPLAY 1.021277 (475 4075);
PAINT ORANGE (475 4075);
DISPLAY INVISIBLE (475 4075);
FORCEPROP 1 LAST OFFPAGE TRUE
J 0
(625 3875);
DISPLAY 1.170213 (625 3875);
PAINT GREEN (625 3875);
DISPLAY INVISIBLE (625 3875);
FORCEPROP 1 LAST COMMENT_BODY TRUE
J 0
(275 3900);
DISPLAY 1.170213 (275 3900);
PAINT GREEN (275 3900);
DISPLAY INVISIBLE (275 3900);
FORCEADD OFFPAGE..4
(300 3300);
FORCEPROP 2 LAST $XR0 232 
J 0
(486 3300);
DISPLAY 0.638298 (486 3300);
PAINT MONO (486 3300);
FORCEPROP 2 LAST CDS_LIB mstr_standard
J 0
(300 3300);
PAINT ORANGE (300 3300);
DISPLAY INVISIBLE (300 3300);
FORCEPROP 2 LAST PATH I324
J 0
(475 3375);
DISPLAY 1.021277 (475 3375);
PAINT ORANGE (475 3375);
DISPLAY INVISIBLE (475 3375);
FORCEPROP 1 LAST OFFPAGE TRUE
J 0
(625 3175);
DISPLAY 1.170213 (625 3175);
PAINT GREEN (625 3175);
DISPLAY INVISIBLE (625 3175);
FORCEPROP 1 LAST COMMENT_BODY TRUE
J 0
(275 3200);
DISPLAY 1.170213 (275 3200);
PAINT GREEN (275 3200);
DISPLAY INVISIBLE (275 3200);
FORCEADD OFFPAGE..4
R 2
(-4475 2050);
FORCEPROP 2 LAST $XR0 101 
J 0
(-4727 2050);
DISPLAY 0.638298 (-4727 2050);
PAINT MONO (-4727 2050);
FORCEPROP 2 LAST PATH I325
J 0
(-4425 2125);
DISPLAY 1.021277 (-4425 2125);
PAINT ORANGE (-4425 2125);
DISPLAY INVISIBLE (-4425 2125);
FORCEPROP 2 LAST CDS_LIB mstr_standard
J 0
(-4475 2050);
PAINT ORANGE (-4475 2050);
DISPLAY INVISIBLE (-4475 2050);
FORCEPROP 1 LAST OFFPAGE TRUE
J 2
(-4800 1925);
DISPLAY 1.170213 (-4800 1925);
PAINT GREEN (-4800 1925);
DISPLAY INVISIBLE (-4800 1925);
FORCEPROP 1 LAST COMMENT_BODY TRUE
J 2
(-4450 1950);
DISPLAY 1.170213 (-4450 1950);
PAINT GREEN (-4450 1950);
DISPLAY INVISIBLE (-4450 1950);
FORCEADD OFFPAGE..4
R 2
(-4475 1950);
FORCEPROP 2 LAST $XR1 112 
J 0
(-4847 1950);
DISPLAY 0.638298 (-4847 1950);
PAINT MONO (-4847 1950);
FORCEPROP 2 LAST $XR0 201 
J 0
(-4727 1950);
DISPLAY 0.638298 (-4727 1950);
PAINT MONO (-4727 1950);
FORCEPROP 2 LAST PATH I326
J 0
(-4425 2025);
DISPLAY 1.021277 (-4425 2025);
PAINT ORANGE (-4425 2025);
DISPLAY INVISIBLE (-4425 2025);
FORCEPROP 2 LAST CDS_LIB mstr_standard
J 0
(-4475 1950);
PAINT ORANGE (-4475 1950);
DISPLAY INVISIBLE (-4475 1950);
FORCEPROP 1 LAST OFFPAGE TRUE
J 2
(-4800 1825);
DISPLAY 1.170213 (-4800 1825);
PAINT GREEN (-4800 1825);
DISPLAY INVISIBLE (-4800 1825);
FORCEPROP 1 LAST COMMENT_BODY TRUE
J 2
(-4450 1850);
DISPLAY 1.170213 (-4450 1850);
PAINT GREEN (-4450 1850);
DISPLAY INVISIBLE (-4450 1850);
FORCEADD OFFPAGE..4
R 2
(-4475 1900);
FORCEPROP 2 LAST $XR0 193 
J 0
(-4727 1900);
DISPLAY 0.638298 (-4727 1900);
PAINT MONO (-4727 1900);
FORCEPROP 2 LAST PATH I327
J 0
(-4425 1975);
DISPLAY 1.021277 (-4425 1975);
PAINT ORANGE (-4425 1975);
DISPLAY INVISIBLE (-4425 1975);
FORCEPROP 2 LAST CDS_LIB mstr_standard
J 0
(-4475 1900);
PAINT ORANGE (-4475 1900);
DISPLAY INVISIBLE (-4475 1900);
FORCEPROP 1 LAST OFFPAGE TRUE
J 2
(-4800 1775);
DISPLAY 1.170213 (-4800 1775);
PAINT GREEN (-4800 1775);
DISPLAY INVISIBLE (-4800 1775);
FORCEPROP 1 LAST COMMENT_BODY TRUE
J 2
(-4450 1800);
DISPLAY 1.170213 (-4450 1800);
PAINT GREEN (-4450 1800);
DISPLAY INVISIBLE (-4450 1800);
FORCEADD OFFPAGE..4
(300 1550);
FORCEPROP 2 LAST $XR3 247 
J 0
(816 1550);
DISPLAY 0.638298 (816 1550);
PAINT MONO (816 1550);
FORCEPROP 2 LAST $XR2 120 
J 0
(696 1550);
DISPLAY 0.638298 (696 1550);
PAINT MONO (696 1550);
FORCEPROP 2 LAST $XR1 147 
J 0
(576 1550);
DISPLAY 0.638298 (576 1550);
PAINT MONO (576 1550);
FORCEPROP 2 LAST $XR0 92 
J 0
(486 1550);
DISPLAY 0.638298 (486 1550);
PAINT MONO (486 1550);
FORCEPROP 2 LAST CDS_LIB mstr_standard
J 0
(300 1550);
PAINT ORANGE (300 1550);
DISPLAY INVISIBLE (300 1550);
FORCEPROP 2 LAST PATH I328
J 0
(475 1625);
DISPLAY 1.021277 (475 1625);
PAINT ORANGE (475 1625);
DISPLAY INVISIBLE (475 1625);
FORCEPROP 1 LAST OFFPAGE TRUE
J 0
(625 1425);
DISPLAY 1.170213 (625 1425);
PAINT GREEN (625 1425);
DISPLAY INVISIBLE (625 1425);
FORCEPROP 1 LAST COMMENT_BODY TRUE
J 0
(275 1450);
DISPLAY 1.170213 (275 1450);
PAINT GREEN (275 1450);
DISPLAY INVISIBLE (275 1450);
FORCEADD OFFPAGE..4
R 2
(-4475 2200);
FORCEPROP 2 LAST $XR0 144 
J 0
(-4727 2200);
DISPLAY 0.638298 (-4727 2200);
PAINT MONO (-4727 2200);
FORCEPROP 2 LAST PATH I329
J 0
(-4725 2250);
DISPLAY 1.021277 (-4725 2250);
PAINT ORANGE (-4725 2250);
DISPLAY INVISIBLE (-4725 2250);
FORCEPROP 2 LAST CDS_LIB mstr_standard
J 0
(-4475 2200);
PAINT ORANGE (-4475 2200);
DISPLAY INVISIBLE (-4475 2200);
FORCEPROP 1 LAST OFFPAGE TRUE
J 2
(-4800 2075);
DISPLAY 1.170213 (-4800 2075);
PAINT GREEN (-4800 2075);
DISPLAY INVISIBLE (-4800 2075);
FORCEPROP 1 LAST COMMENT_BODY TRUE
J 2
(-4450 2100);
DISPLAY 1.170213 (-4450 2100);
PAINT GREEN (-4450 2100);
DISPLAY INVISIBLE (-4450 2100);
FORCEADD OFFPAGE..1
(-4475 2550);
FORCEPROP 2 LAST $XR1 145 
J 0
(-4847 2550);
DISPLAY 0.638298 (-4847 2550);
PAINT MONO (-4847 2550);
FORCEPROP 2 LAST $XR0 158 
J 0
(-4727 2550);
DISPLAY 0.638298 (-4727 2550);
PAINT MONO (-4727 2550);
FORCEPROP 2 LAST PATH I332
J 0
(-4425 2625);
DISPLAY 1.021277 (-4425 2625);
PAINT ORANGE (-4425 2625);
DISPLAY INVISIBLE (-4425 2625);
FORCEPROP 2 LAST CDS_LIB mstr_standard
J 0
(-4475 2550);
PAINT ORANGE (-4475 2550);
DISPLAY INVISIBLE (-4475 2550);
FORCEPROP 1 LAST OFFPAGE TRUE
J 0
(-4150 2425);
DISPLAY 0.872340 (-4150 2425);
PAINT GREEN (-4150 2425);
DISPLAY INVISIBLE (-4150 2425);
FORCEPROP 1 LAST COMMENT_BODY TRUE
J 0
(-4350 2450);
DISPLAY 0.872340 (-4350 2450);
PAINT GREEN (-4350 2450);
DISPLAY INVISIBLE (-4350 2450);
FORCEADD OFFPAGE..5
(-4475 2500);
FORCEPROP 2 LAST $XR1 158 
J 0
(-4850 2500);
DISPLAY 0.638298 (-4850 2500);
PAINT MONO (-4850 2500);
FORCEPROP 2 LAST $XR0 145 
J 0
(-4730 2500);
DISPLAY 0.638298 (-4730 2500);
PAINT MONO (-4730 2500);
FORCEPROP 2 LAST PATH I333
J 0
(-4425 2575);
DISPLAY 1.021277 (-4425 2575);
PAINT ORANGE (-4425 2575);
DISPLAY INVISIBLE (-4425 2575);
FORCEPROP 2 LAST CDS_LIB mstr_standard
J 0
(-4475 2500);
PAINT ORANGE (-4475 2500);
DISPLAY INVISIBLE (-4475 2500);
FORCEPROP 1 LAST OFFPAGE TRUE
J 0
(-4150 2375);
DISPLAY 0.872340 (-4150 2375);
PAINT GREEN (-4150 2375);
DISPLAY INVISIBLE (-4150 2375);
FORCEPROP 1 LAST COMMENT_BODY TRUE
J 0
(-4375 2425);
DISPLAY 0.872340 (-4375 2425);
PAINT GREEN (-4375 2425);
DISPLAY INVISIBLE (-4375 2425);
FORCEADD OFFPAGE..1
(-4475 2450);
FORCEPROP 2 LAST $XR1 145 
J 0
(-4847 2450);
DISPLAY 0.638298 (-4847 2450);
PAINT MONO (-4847 2450);
FORCEPROP 2 LAST $XR0 158 
J 0
(-4727 2450);
DISPLAY 0.638298 (-4727 2450);
PAINT MONO (-4727 2450);
FORCEPROP 2 LAST PATH I334
J 0
(-4425 2525);
DISPLAY 1.021277 (-4425 2525);
PAINT ORANGE (-4425 2525);
DISPLAY INVISIBLE (-4425 2525);
FORCEPROP 2 LAST CDS_LIB mstr_standard
J 0
(-4475 2450);
PAINT ORANGE (-4475 2450);
DISPLAY INVISIBLE (-4475 2450);
FORCEPROP 1 LAST OFFPAGE TRUE
J 0
(-4150 2325);
DISPLAY 0.872340 (-4150 2325);
PAINT GREEN (-4150 2325);
DISPLAY INVISIBLE (-4150 2325);
FORCEPROP 1 LAST COMMENT_BODY TRUE
J 0
(-4350 2350);
DISPLAY 0.872340 (-4350 2350);
PAINT GREEN (-4350 2350);
DISPLAY INVISIBLE (-4350 2350);
FORCEADD OFFPAGE..5
(-4475 2400);
FORCEPROP 2 LAST $XR2 158 
J 0
(-4970 2400);
DISPLAY 0.638298 (-4970 2400);
PAINT MONO (-4970 2400);
FORCEPROP 2 LAST $XR1 150 
J 0
(-4850 2400);
DISPLAY 0.638298 (-4850 2400);
PAINT MONO (-4850 2400);
FORCEPROP 2 LAST $XR0 145 
J 0
(-4730 2400);
DISPLAY 0.638298 (-4730 2400);
PAINT MONO (-4730 2400);
FORCEPROP 2 LAST PATH I335
J 0
(-4425 2475);
DISPLAY 1.021277 (-4425 2475);
PAINT ORANGE (-4425 2475);
DISPLAY INVISIBLE (-4425 2475);
FORCEPROP 2 LAST CDS_LIB mstr_standard
J 0
(-4475 2400);
PAINT ORANGE (-4475 2400);
DISPLAY INVISIBLE (-4475 2400);
FORCEPROP 1 LAST OFFPAGE TRUE
J 0
(-4150 2275);
DISPLAY 0.872340 (-4150 2275);
PAINT GREEN (-4150 2275);
DISPLAY INVISIBLE (-4150 2275);
FORCEPROP 1 LAST COMMENT_BODY TRUE
J 0
(-4375 2325);
DISPLAY 0.872340 (-4375 2325);
PAINT GREEN (-4375 2325);
DISPLAY INVISIBLE (-4375 2325);
FORCEADD OFFPAGE..2
R 2
(-4475 1400);
FORCEPROP 2 LAST $XR1 119 
J 0
(-4850 1400);
DISPLAY 0.638298 (-4850 1400);
PAINT MONO (-4850 1400);
FORCEPROP 2 LAST $XR0 183 
J 0
(-4730 1400);
DISPLAY 0.638298 (-4730 1400);
PAINT MONO (-4730 1400);
FORCEPROP 2 LAST PATH I336
J 0
(-4425 1475);
DISPLAY 1.021277 (-4425 1475);
PAINT ORANGE (-4425 1475);
DISPLAY INVISIBLE (-4425 1475);
FORCEPROP 2 LAST CDS_LIB mstr_standard
J 0
(-4475 1400);
PAINT ORANGE (-4475 1400);
DISPLAY INVISIBLE (-4475 1400);
FORCEPROP 1 LAST OFFPAGE TRUE
J 2
(-4800 1275);
DISPLAY 1.170213 (-4800 1275);
PAINT GREEN (-4800 1275);
DISPLAY INVISIBLE (-4800 1275);
FORCEPROP 1 LAST COMMENT_BODY TRUE
J 2
(-4430 1305);
DISPLAY 1.170213 (-4430 1305);
PAINT GREEN (-4430 1305);
DISPLAY INVISIBLE (-4430 1305);
FORCEADD OFFPAGE..3
(-500 5200);
FORCEPROP 2 LASTPIN (-550 5200) SIG_NAME RST_RSMRST_N
J 2
(-560 5210);
DISPLAY 0.617021 (-560 5210);
PAINT ORANGE (-560 5210);
FORCEPROP 2 LAST $XR3 147 
J 0
(74 5200);
DISPLAY 0.638298 (74 5200);
PAINT MONO (74 5200);
FORCEPROP 2 LAST $XR2 118 
J 0
(-46 5200);
DISPLAY 0.638298 (-46 5200);
PAINT MONO (-46 5200);
FORCEPROP 2 LAST $XR1 111 
J 0
(-166 5200);
DISPLAY 0.638298 (-166 5200);
PAINT MONO (-166 5200);
FORCEPROP 2 LAST $XR0 192 
J 0
(-286 5200);
DISPLAY 0.638298 (-286 5200);
PAINT MONO (-286 5200);
FORCEPROP 2 LAST PATH I337
J 0
(-325 5275);
DISPLAY 1.021277 (-325 5275);
PAINT ORANGE (-325 5275);
DISPLAY INVISIBLE (-325 5275);
FORCEPROP 2 LAST CDS_LIB mstr_standard
J 0
(-500 5200);
PAINT ORANGE (-500 5200);
DISPLAY INVISIBLE (-500 5200);
FORCEPROP 2 LAST ROOM PLD
J 0
(-750 5250);
DISPLAY 1.617021 (-750 5250);
PAINT WHITE (-750 5250);
DISPLAY INVISIBLE (-750 5250);
FORCEPROP 2 LAST BOM_COST SB_RESET
J 0
(-750 5250);
DISPLAY 1.617021 (-750 5250);
PAINT WHITE (-750 5250);
DISPLAY INVISIBLE (-750 5250);
FORCEPROP 1 LAST OFFPAGE TRUE
J 0
(-175 5075);
DISPLAY 0.872340 (-175 5075);
PAINT GREEN (-175 5075);
DISPLAY INVISIBLE (-175 5075);
FORCEPROP 1 LAST COMMENT_BODY TRUE
J 0
(-550 5100);
DISPLAY 0.872340 (-550 5100);
PAINT GREEN (-550 5100);
DISPLAY INVISIBLE (-550 5100);
FORCEADD RES..1
(-1350 5200);
FORCEPROP 1 LAST MATERIAL CHIP
J 0
(-1350 5050);
DISPLAY 0.617021 (-1350 5050);
PAINT SKYBLUE (-1350 5050);
FORCEPROP 1 LAST LOCATION R2R2
J 0
(-1575 5225);
DISPLAY 0.617021 (-1575 5225);
PAINT AQUA (-1575 5225);
FORCEPROP 1 LAST VALUE 33.2
J 2
(-1450 5100);
DISPLAY 0.617021 (-1450 5100);
PAINT SKYBLUE (-1450 5100);
FORCEPROP 1 LAST PACK_TYPE 0402
J 0
(-1275 5100);
DISPLAY 0.617021 (-1275 5100);
PAINT SKYBLUE (-1275 5100);
FORCEPROP 1 LAST PART_NUMBER G21796-074
J 0
(-1500 5150);
DISPLAY 0.617021 (-1500 5150);
PAINT BLUE (-1500 5150);
FORCEPROP 1 LAST TOLERANCE 1%
J 0
(-1400 5100);
DISPLAY 0.617021 (-1400 5100);
PAINT SKYBLUE (-1400 5100);
FORCEPROP 1 LAST WATTAGE 1/16W
J 2
(-1375 5050);
DISPLAY 0.617021 (-1375 5050);
PAINT SKYBLUE (-1375 5050);
FORCEPROP 2 LAST CDS_LIB mstr_discrete
J 0
(-1350 5200);
PAINT ORANGE (-1350 5200);
DISPLAY INVISIBLE (-1350 5200);
FORCEPROP 0 LAST BOM_COST CPLD
J 0
(-1575 5325);
DISPLAY 1.021277 (-1575 5325);
PAINT ORANGE (-1575 5325);
DISPLAY INVISIBLE (-1575 5325);
FORCEPROP 2 LAST CDS_SEC 1
J 0
(-1400 5400);
PAINT MONO (-1400 5400);
DISPLAY INVISIBLE (-1400 5400);
FORCEPROP 2 LAST $SEC 1
J 0
(-1400 5400);
PAINT MONO (-1400 5400);
DISPLAY INVISIBLE (-1400 5400);
FORCEPROP 2 LAST CDS_LOCATION R2R2
J 0
(-1575 5225);
DISPLAY 0.617021 (-1575 5225);
PAINT AQUA (-1575 5225);
DISPLAY INVISIBLE (-1575 5225);
FORCEPROP 1 LAST PATH I338
J 0
(-1400 5350);
DISPLAY 0.978723 (-1400 5350);
PAINT WHITE (-1400 5350);
DISPLAY INVISIBLE (-1400 5350);
FORCEPROP 2 LAST ROOM CPLD
J 0
(-1400 5300);
DISPLAY 1.361702 (-1400 5300);
PAINT ORANGE (-1400 5300);
DISPLAY INVISIBLE (-1400 5300);
FORCEPROP 1 LASTPIN (-1250 5200) $PN 2
J 0
(-1288 5212);
DISPLAY 0.787234 (-1288 5212);
PAINT ORANGE (-1288 5212);
DISPLAY INVISIBLE (-1288 5212);
FORCEPROP 1 LASTPIN (-1450 5200) $PN 1
J 0
(-1438 5212);
DISPLAY 0.787234 (-1438 5212);
PAINT ORANGE (-1438 5212);
DISPLAY INVISIBLE (-1438 5212);
FORCEADD OFFPAGE..6
(-2250 5200);
FORCEPROP 2 LASTPIN (-2200 5200) SIG_NAME RST_RSMRST_R_N
J 0
(-2210 5210);
DISPLAY 0.617021 (-2210 5210);
PAINT ORANGE (-2210 5210);
FORCEPROP 2 LAST $XR0 190 
J 0
(-2530 5200);
DISPLAY 0.638298 (-2530 5200);
PAINT MONO (-2530 5200);
FORCEPROP 2 LAST PATH I339
J 0
(-2200 5275);
DISPLAY 1.021277 (-2200 5275);
PAINT ORANGE (-2200 5275);
DISPLAY INVISIBLE (-2200 5275);
FORCEPROP 2 LAST CDS_LIB mstr_standard
J 0
(-2250 5200);
PAINT ORANGE (-2250 5200);
DISPLAY INVISIBLE (-2250 5200);
FORCEPROP 2 LAST ROOM PLD
J 0
(-2500 5250);
DISPLAY 1.617021 (-2500 5250);
PAINT WHITE (-2500 5250);
DISPLAY INVISIBLE (-2500 5250);
FORCEPROP 2 LAST BOM_COST SB_RESET
J 0
(-2500 5250);
DISPLAY 1.617021 (-2500 5250);
PAINT WHITE (-2500 5250);
DISPLAY INVISIBLE (-2500 5250);
FORCEPROP 1 LAST OFFPAGE TRUE
J 0
(-1925 5075);
DISPLAY 0.872340 (-1925 5075);
PAINT GREEN (-1925 5075);
DISPLAY INVISIBLE (-1925 5075);
FORCEPROP 1 LAST COMMENT_BODY TRUE
J 0
(-2150 5125);
DISPLAY 0.872340 (-2150 5125);
PAINT GREEN (-2150 5125);
DISPLAY INVISIBLE (-2150 5125);
FORCEADD OFFPAGE..2
(300 1750);
FORCEPROP 2 LAST $XR0 104 
J 0
(489 1750);
DISPLAY 0.638298 (489 1750);
PAINT MONO (489 1750);
FORCEPROP 2 LAST CDS_LIB mstr_standard
J 0
(300 1750);
PAINT ORANGE (300 1750);
DISPLAY INVISIBLE (300 1750);
FORCEPROP 2 LAST PATH I340
J 0
(475 1825);
DISPLAY 1.021277 (475 1825);
PAINT ORANGE (475 1825);
DISPLAY INVISIBLE (475 1825);
FORCEPROP 1 LAST OFFPAGE TRUE
J 0
(625 1625);
DISPLAY 1.170213 (625 1625);
PAINT GREEN (625 1625);
DISPLAY INVISIBLE (625 1625);
FORCEPROP 1 LAST COMMENT_BODY TRUE
J 0
(255 1655);
DISPLAY 1.170213 (255 1655);
PAINT GREEN (255 1655);
DISPLAY INVISIBLE (255 1655);
FORCEADD OFFPAGE..4
R 2
(-4475 1650);
FORCEPROP 2 LAST $XR1 147 
J 0
(-4847 1650);
DISPLAY 0.638298 (-4847 1650);
PAINT MONO (-4847 1650);
FORCEPROP 2 LAST $XR0 119 
J 0
(-4727 1650);
DISPLAY 0.638298 (-4727 1650);
PAINT MONO (-4727 1650);
FORCEPROP 2 LAST PATH I341
J 0
(-4425 1725);
DISPLAY 1.021277 (-4425 1725);
PAINT ORANGE (-4425 1725);
DISPLAY INVISIBLE (-4425 1725);
FORCEPROP 2 LAST CDS_LIB mstr_standard
J 0
(-4475 1650);
PAINT ORANGE (-4475 1650);
DISPLAY INVISIBLE (-4475 1650);
FORCEPROP 1 LAST OFFPAGE TRUE
J 2
(-4800 1525);
DISPLAY 1.170213 (-4800 1525);
PAINT GREEN (-4800 1525);
DISPLAY INVISIBLE (-4800 1525);
FORCEPROP 1 LAST COMMENT_BODY TRUE
J 2
(-4450 1550);
DISPLAY 1.170213 (-4450 1550);
PAINT GREEN (-4450 1550);
DISPLAY INVISIBLE (-4450 1550);
FORCEADD OFFPAGE..4
(300 4600);
FORCEPROP 2 LAST $XR1 133 
J 0
(606 4600);
DISPLAY 0.638298 (606 4600);
PAINT MONO (606 4600);
FORCEPROP 2 LAST $XR0 119 
J 0
(486 4600);
DISPLAY 0.638298 (486 4600);
PAINT MONO (486 4600);
FORCEPROP 2 LAST CDS_LIB mstr_standard
J 0
(300 4600);
PAINT ORANGE (300 4600);
DISPLAY INVISIBLE (300 4600);
FORCEPROP 2 LAST PATH I342
J 0
(475 4675);
DISPLAY 1.021277 (475 4675);
PAINT ORANGE (475 4675);
DISPLAY INVISIBLE (475 4675);
FORCEPROP 1 LAST OFFPAGE TRUE
J 0
(625 4475);
DISPLAY 1.170213 (625 4475);
PAINT GREEN (625 4475);
DISPLAY INVISIBLE (625 4475);
FORCEPROP 1 LAST COMMENT_BODY TRUE
J 0
(275 4500);
DISPLAY 1.170213 (275 4500);
PAINT GREEN (275 4500);
DISPLAY INVISIBLE (275 4500);
FORCEADD OFFPAGE..4
(300 4450);
FORCEPROP 2 LAST $XR1 133 
J 0
(606 4450);
DISPLAY 0.638298 (606 4450);
PAINT MONO (606 4450);
FORCEPROP 2 LAST $XR0 120 
J 0
(486 4450);
DISPLAY 0.638298 (486 4450);
PAINT MONO (486 4450);
FORCEPROP 2 LAST CDS_LIB mstr_standard
J 0
(300 4450);
PAINT ORANGE (300 4450);
DISPLAY INVISIBLE (300 4450);
FORCEPROP 2 LAST PATH I343
J 0
(475 4525);
DISPLAY 1.021277 (475 4525);
PAINT ORANGE (475 4525);
DISPLAY INVISIBLE (475 4525);
FORCEPROP 1 LAST OFFPAGE TRUE
J 0
(625 4325);
DISPLAY 1.170213 (625 4325);
PAINT GREEN (625 4325);
DISPLAY INVISIBLE (625 4325);
FORCEPROP 1 LAST COMMENT_BODY TRUE
J 0
(275 4350);
DISPLAY 1.170213 (275 4350);
PAINT GREEN (275 4350);
DISPLAY INVISIBLE (275 4350);
FORCEADD OFFPAGE..4
(300 4050);
FORCEPROP 2 LAST $XR0 135 
J 0
(486 4050);
DISPLAY 0.638298 (486 4050);
PAINT MONO (486 4050);
FORCEPROP 2 LAST CDS_LIB mstr_standard
J 0
(300 4050);
PAINT ORANGE (300 4050);
DISPLAY INVISIBLE (300 4050);
FORCEPROP 2 LAST PATH I344
J 0
(475 4125);
DISPLAY 1.021277 (475 4125);
PAINT ORANGE (475 4125);
DISPLAY INVISIBLE (475 4125);
FORCEPROP 1 LAST OFFPAGE TRUE
J 0
(625 3925);
DISPLAY 1.170213 (625 3925);
PAINT GREEN (625 3925);
DISPLAY INVISIBLE (625 3925);
FORCEPROP 1 LAST COMMENT_BODY TRUE
J 0
(275 3950);
DISPLAY 1.170213 (275 3950);
PAINT GREEN (275 3950);
DISPLAY INVISIBLE (275 3950);
FORCEADD OFFPAGE..1
(-4475 4150);
FORCEPROP 2 LASTPIN (-4425 4150) SIG_NAME FM_MEM_EVENT_FUNC
J 0
(-4385 4160);
DISPLAY 0.617021 (-4385 4160);
PAINT ORANGE (-4385 4160);
FORCEPROP 2 LAST $XR0 192 
J 0
(-4727 4150);
DISPLAY 0.638298 (-4727 4150);
PAINT MONO (-4727 4150);
FORCEPROP 2 LAST PATH I345
J 0
(-4425 4225);
DISPLAY 1.021277 (-4425 4225);
PAINT ORANGE (-4425 4225);
DISPLAY INVISIBLE (-4425 4225);
FORCEPROP 2 LAST CDS_LIB mstr_standard
J 0
(-4475 4150);
PAINT ORANGE (-4475 4150);
DISPLAY INVISIBLE (-4475 4150);
FORCEPROP 1 LAST OFFPAGE TRUE
J 0
(-4150 4025);
DISPLAY 0.872340 (-4150 4025);
PAINT GREEN (-4150 4025);
DISPLAY INVISIBLE (-4150 4025);
FORCEPROP 1 LAST COMMENT_BODY TRUE
J 0
(-4350 4050);
DISPLAY 0.872340 (-4350 4050);
PAINT GREEN (-4350 4050);
DISPLAY INVISIBLE (-4350 4050);
FORCEADD OFFPAGE..5
(-4475 2000);
FORCEPROP 2 LAST $XR0 126 
J 0
(-4730 2000);
DISPLAY 0.638298 (-4730 2000);
PAINT MONO (-4730 2000);
FORCEPROP 2 LAST CDS_LIB mstr_standard
J 0
(-4475 2000);
PAINT ORANGE (-4475 2000);
DISPLAY INVISIBLE (-4475 2000);
FORCEPROP 2 LAST PATH I346
J 0
(-4425 2075);
DISPLAY 1.021277 (-4425 2075);
PAINT ORANGE (-4425 2075);
DISPLAY INVISIBLE (-4425 2075);
FORCEPROP 1 LAST OFFPAGE TRUE
J 0
(-4150 1875);
DISPLAY 0.872340 (-4150 1875);
PAINT GREEN (-4150 1875);
DISPLAY INVISIBLE (-4150 1875);
FORCEPROP 1 LAST COMMENT_BODY TRUE
J 0
(-4375 1925);
DISPLAY 0.872340 (-4375 1925);
PAINT GREEN (-4375 1925);
DISPLAY INVISIBLE (-4375 1925);
FORCEADD OFFPAGE..4
(300 3750);
FORCEPROP 2 LAST $XR1 120 
J 0
(486 3714);
DISPLAY 0.638298 (486 3714);
PAINT MONO (486 3714);
FORCEPROP 2 LAST $XR0 176 
J 0
(486 3750);
DISPLAY 0.638298 (486 3750);
PAINT MONO (486 3750);
FORCEPROP 2 LAST CDS_LIB mstr_standard
J 0
(300 3750);
PAINT MONO (300 3750);
DISPLAY INVISIBLE (300 3750);
FORCEPROP 2 LAST PATH I347
J 0
(475 3825);
DISPLAY 1.021277 (475 3825);
PAINT ORANGE (475 3825);
DISPLAY INVISIBLE (475 3825);
FORCEPROP 1 LAST OFFPAGE TRUE
J 0
(625 3625);
DISPLAY 1.170213 (625 3625);
PAINT GREEN (625 3625);
DISPLAY INVISIBLE (625 3625);
FORCEPROP 1 LAST COMMENT_BODY TRUE
J 0
(275 3650);
DISPLAY 1.170213 (275 3650);
PAINT GREEN (275 3650);
DISPLAY INVISIBLE (275 3650);
FORCEADD OFFPAGE..2
(300 3350);
FORCEPROP 2 LAST $XR0 176 
J 0
(489 3350);
DISPLAY 0.638298 (489 3350);
PAINT MONO (489 3350);
FORCEPROP 2 LAST PATH I348
J 0
(475 3425);
DISPLAY 1.021277 (475 3425);
PAINT ORANGE (475 3425);
DISPLAY INVISIBLE (475 3425);
FORCEPROP 2 LAST CDS_LIB mstr_standard
J 0
(300 3350);
PAINT MONO (300 3350);
DISPLAY INVISIBLE (300 3350);
FORCEPROP 1 LAST OFFPAGE TRUE
J 0
(625 3225);
DISPLAY 1.170213 (625 3225);
PAINT GREEN (625 3225);
DISPLAY INVISIBLE (625 3225);
FORCEPROP 1 LAST COMMENT_BODY TRUE
J 0
(255 3255);
DISPLAY 1.170213 (255 3255);
PAINT GREEN (255 3255);
DISPLAY INVISIBLE (255 3255);
FORCEADD RES..2
(-1800 5000);
FORCEPROP 1 LAST PACK_TYPE 0402
J 0
(-1760 4825);
DISPLAY 0.617021 (-1760 4825);
PAINT SKYBLUE (-1760 4825);
FORCEPROP 1 LASTPIN (-1800 4900) $PN 2
J 0
(-1795 4910);
DISPLAY 0.617021 (-1795 4910);
PAINT ORANGE (-1795 4910);
FORCEPROP 1 LAST MATERIAL EMPTY
J 0
(-1760 4925);
DISPLAY 0.617021 (-1760 4925);
PAINT RED (-1760 4925);
FORCEPROP 1 LAST WATTAGE 1/16W
J 0
(-1760 4975);
DISPLAY 0.617021 (-1760 4975);
PAINT SKYBLUE (-1760 4975);
FORCEPROP 1 LAST TOLERANCE 1%
J 0
(-1755 5025);
DISPLAY 0.617021 (-1755 5025);
PAINT SKYBLUE (-1755 5025);
FORCEPROP 1 LASTPIN (-1800 5100) $PN 1
J 0
(-1795 5062);
DISPLAY 0.617021 (-1795 5062);
PAINT ORANGE (-1795 5062);
FORCEPROP 1 LAST LOCATION R1W26
J 0
(-1755 5125);
DISPLAY 0.617021 (-1755 5125);
PAINT AQUA (-1755 5125);
FORCEPROP 1 LAST VALUE 10.0K
J 0
(-1755 5075);
DISPLAY 0.617021 (-1755 5075);
PAINT SKYBLUE (-1755 5075);
FORCEPROP 1 LAST PART_NUMBER G21796-016
J 0
(-1760 4875);
DISPLAY 0.617021 (-1760 4875);
PAINT BLUE (-1760 4875);
FORCEPROP 2 LAST CDS_LOCATION R1W26
J 0
(-1755 5125);
DISPLAY 0.617021 (-1755 5125);
PAINT AQUA (-1755 5125);
DISPLAY INVISIBLE (-1755 5125);
FORCEPROP 1 LAST PATH I349
J 0
(-1750 5175);
DISPLAY 0.978723 (-1750 5175);
PAINT WHITE (-1750 5175);
DISPLAY INVISIBLE (-1750 5175);
FORCEPROP 2 LAST ROOM DB1200ZL
J 0
(-1750 5225);
DISPLAY 1.021277 (-1750 5225);
PAINT ORANGE (-1750 5225);
DISPLAY INVISIBLE (-1750 5225);
FORCEPROP 2 LAST SEC 1
J 0
(-1750 5225);
DISPLAY 0.680851 (-1750 5225);
PAINT MONO (-1750 5225);
DISPLAY INVISIBLE (-1750 5225);
FORCEPROP 2 LAST SEC_TYPE 0402
J 0
(-1750 5225);
DISPLAY 1.021277 (-1750 5225);
PAINT ORANGE (-1750 5225);
DISPLAY INVISIBLE (-1750 5225);
FORCEPROP 2 LAST BOM_COST SYS_CLOCK
J 0
(-1750 5325);
DISPLAY 1.021277 (-1750 5325);
PAINT ORANGE (-1750 5325);
DISPLAY INVISIBLE (-1750 5325);
FORCEPROP 2 LAST CDS_LIB mstr_discrete
J 0
(-1800 5000);
PAINT ORANGE (-1800 5000);
DISPLAY INVISIBLE (-1800 5000);
FORCEADD GND..1
(-1800 4800);
FORCEPROP 3 LASTPIN (-1800 4850) SIG_NAME GND\g
J 0
(-1790 4860);
DISPLAY 0.659574 (-1790 4860);
PAINT MONO (-1790 4860);
DISPLAY INVISIBLE (-1790 4860);
FORCEPROP 1 LAST PATH I350
J 0
(-1725 4800);
DISPLAY 0.872340 (-1725 4800);
PAINT AQUA (-1725 4800);
DISPLAY INVISIBLE (-1725 4800);
FORCEPROP 2 LAST ROOM DB1200ZL
J 0
(-2125 4875);
DISPLAY 1.127660 (-2125 4875);
PAINT WHITE (-2125 4875);
DISPLAY INVISIBLE (-2125 4875);
FORCEPROP 2 LAST BOM_COST SYS_CLOCK
J 0
(-2250 4875);
DISPLAY 1.617021 (-2250 4875);
PAINT WHITE (-2250 4875);
DISPLAY INVISIBLE (-2250 4875);
FORCEPROP 1 LAST VOLTAGE 0.0V
J 0
(-1845 4757);
DISPLAY 0.340426 (-1845 4757);
PAINT SKYBLUE (-1845 4757);
DISPLAY INVISIBLE (-1845 4757);
FORCEPROP 2 LAST CDS_LIB mstr_symbols
J 0
(-1800 4800);
PAINT ORANGE (-1800 4800);
DISPLAY INVISIBLE (-1800 4800);
FORCEPROP 1 LAST SIZE 1B
J 0
(-1725 4750);
DISPLAY 1.127660 (-1725 4750);
PAINT ORANGE (-1725 4750);
DISPLAY INVISIBLE (-1725 4750);
FORCEPROP 1 LAST BODY_TYPE PLUMBING
J 0
(-1845 4757);
DISPLAY 0.340426 (-1845 4757);
PAINT GREEN (-1845 4757);
DISPLAY INVISIBLE (-1845 4757);
FORCEPROP 1 LAST HDL_POWER GND
J 0
(-1800 4950);
PAINT GREEN (-1800 4950);
DISPLAY INVISIBLE (-1800 4950);
FORCEADD RES..1
(-3300 3900);
FORCEPROP 1 LASTPIN (-3400 3900) $PN 1
J 0
(-3388 3912);
DISPLAY 0.617021 (-3388 3912);
PAINT ORANGE (-3388 3912);
FORCEPROP 1 LASTPIN (-3200 3900) $PN 2
J 0
(-3238 3912);
DISPLAY 0.617021 (-3238 3912);
PAINT ORANGE (-3238 3912);
FORCEPROP 1 LAST PART_NUMBER G21497-005
J 0
(-3800 3850);
DISPLAY 0.617021 (-3800 3850);
PAINT BLUE (-3800 3850);
FORCEPROP 1 LAST MATERIAL CHIP
J 0
(-3550 3850);
DISPLAY 0.617021 (-3550 3850);
PAINT SKYBLUE (-3550 3850);
FORCEPROP 1 LAST WATTAGE 1/16W
J 0
(-4000 3850);
DISPLAY 0.638298 (-4000 3850);
PAINT SKYBLUE (-4000 3850);
FORCEPROP 1 LAST LOCATION R1W27
J 0
(-3800 3900);
DISPLAY 0.617021 (-3800 3900);
PAINT AQUA (-3800 3900);
FORCEPROP 1 LAST VALUE 0.0
J 0
(-3600 3900);
DISPLAY 0.617021 (-3600 3900);
PAINT SKYBLUE (-3600 3900);
FORCEPROP 1 LAST TOLERANCE 5%
J 0
(-3500 3900);
DISPLAY 0.617021 (-3500 3900);
PAINT SKYBLUE (-3500 3900);
FORCEPROP 0 LAST SEC_TYPE 0402
J 0
(-3400 3850);
DISPLAY 0.638298 (-3400 3850);
PAINT SKYBLUE (-3400 3850);
FORCEPROP 2 LAST CDS_LIB mstr_discrete
J 0
(-3300 3900);
PAINT ORANGE (-3300 3900);
DISPLAY INVISIBLE (-3300 3900);
FORCEPROP 2 LAST SEC 1
J 0
(-3350 4100);
DISPLAY 0.680851 (-3350 4100);
PAINT MONO (-3350 4100);
DISPLAY INVISIBLE (-3350 4100);
FORCEPROP 0 LAST ROOM BMC
J 0
(-3350 4100);
DISPLAY 1.021277 (-3350 4100);
PAINT ORANGE (-3350 4100);
DISPLAY INVISIBLE (-3350 4100);
FORCEPROP 0 LAST BOM_COST SM_CONTROLLER
J 0
(-3350 4200);
DISPLAY 1.021277 (-3350 4200);
PAINT ORANGE (-3350 4200);
DISPLAY INVISIBLE (-3350 4200);
FORCEPROP 1 LAST PACK_TYPE 0402
J 0
(-3050 3750);
DISPLAY 0.978723 (-3050 3750);
PAINT SKYBLUE (-3050 3750);
DISPLAY INVISIBLE (-3050 3750);
FORCEPROP 0 LAST CDS_SEC 1
J 0
(-3175 3950);
PAINT MONO (-3175 3950);
DISPLAY INVISIBLE (-3175 3950);
FORCEPROP 1 LAST PATH I351
J 0
(-3350 4050);
DISPLAY 0.978723 (-3350 4050);
PAINT WHITE (-3350 4050);
DISPLAY INVISIBLE (-3350 4050);
FORCEPROP 2 LAST CDS_LOCATION R1W27
J 0
(-3700 3900);
DISPLAY 0.617021 (-3700 3900);
PAINT AQUA (-3700 3900);
DISPLAY INVISIBLE (-3700 3900);
FORCEADD OFFPAGE..4
R 2
(-4475 3700);
FORCEPROP 2 LAST $XR3 175 
J 0
(-5087 3700);
DISPLAY 0.638298 (-5087 3700);
PAINT MONO (-5087 3700);
FORCEPROP 2 LAST $XR2 247 
J 0
(-4967 3700);
DISPLAY 0.638298 (-4967 3700);
PAINT MONO (-4967 3700);
FORCEPROP 2 LAST $XR1 155 
J 0
(-4847 3700);
DISPLAY 0.638298 (-4847 3700);
PAINT MONO (-4847 3700);
FORCEPROP 2 LAST $XR0 111 
J 0
(-4727 3700);
DISPLAY 0.638298 (-4727 3700);
PAINT MONO (-4727 3700);
FORCEPROP 2 LAST CDS_LIB mstr_standard
J 0
(-4475 3700);
PAINT ORANGE (-4475 3700);
DISPLAY INVISIBLE (-4475 3700);
FORCEPROP 2 LAST PATH I352
J 0
(-4675 3750);
DISPLAY 1.021277 (-4675 3750);
PAINT ORANGE (-4675 3750);
DISPLAY INVISIBLE (-4675 3750);
FORCEPROP 1 LAST OFFPAGE TRUE
J 2
(-4800 3575);
DISPLAY 1.170213 (-4800 3575);
PAINT GREEN (-4800 3575);
DISPLAY INVISIBLE (-4800 3575);
FORCEPROP 1 LAST COMMENT_BODY TRUE
J 2
(-4450 3600);
DISPLAY 1.170213 (-4450 3600);
PAINT GREEN (-4450 3600);
DISPLAY INVISIBLE (-4450 3600);
FORCEADD DNS..2
(-1795 4995);
PAINT RED (-1795 4995);
FORCEPROP 2 LAST CDS_LIB mstr_misc
J 0
(-1795 4995);
PAINT ORANGE (-1795 4995);
DISPLAY INVISIBLE (-1795 4995);
FORCEPROP 1 LAST COMMENT_BODY TRUE
R 1
J 0
(-1720 4770);
DISPLAY 0.872340 (-1720 4770);
PAINT GREEN (-1720 4770);
DISPLAY INVISIBLE (-1720 4770);
FORCEADD INTEL_CORP_BPAGE..1
(2650 500);
FORCEPROP 1 LAST CDS_CON_LAST_MODIFIED Fri Jun 16 17:49:10 2017
J 0
(1225 825);
PAINT ORANGE (1225 825);
DISPLAY INVISIBLE (1225 825);
FORCEPROP 1 LAST CUSTOM_TXT_CDS <CURRENT_DESIGN_SHEET> OF <TOTAL_DESIGN_SHEETS>
J 0
(2150 525);
PAINT ORANGE (2150 525);
FORCEPROP 1 LAST CUSTOM_TXT_CDS <CON_LAST_MODIFIED>
J 0
(-1350 600);
PAINT ORANGE (-1350 600);
FORCEPROP 2 LAST CUSTOM_TXT_CDS <XR_PAGE_TITLE>
J 0
(-5240 5750);
DISPLAY 0.638298 (-5240 5750);
PAINT PINK (-5240 5750);
DISPLAY INVISIBLE (-5240 5750);
FORCEPROP 1 LAST SCH_TITLE CPLD (1 OF 3)
J 0
(-5300 550);
DISPLAY 1.212766 (-5300 550);
PAINT ORANGE (-5300 550);
FORCEPROP 2 LAST PAGE_BORDER TRUE
J 0
(-5240 5750);
DISPLAY 0.851064 (-5240 5750);
PAINT PINK (-5240 5750);
DISPLAY INVISIBLE (-5240 5750);
FORCEPROP 2 LAST CDS_LIB mstr_symbols
J 0
(2650 500);
PAINT MONO (2650 500);
DISPLAY INVISIBLE (2650 500);
FORCEPROP 1 LAST COMMENT_BODY TRUE
J 0
(2662 512);
DISPLAY 0.468085 (2662 512);
PAINT GREEN (2662 512);
DISPLAY INVISIBLE (2662 512);
FORCEPROP 2 LAST CDS_XR_PAGE_TITLE CR-190 : @BASEBOARD_FAB2_LIB.BASEBOARD_FAB2(SCH_1):PAGE190
J 0
(-5240 5750);
DISPLAY 0.638298 (-5240 5750);
PAINT PINK (-5240 5750);
DISPLAY INVISIBLE (-5240 5750);
WIRE 16 -1 (-1800 4900)(-1800 4850);
WIRE 16 -1 (-2550 4000)(-4425 4000);
FORCEPROP 0 LAST SIG_NAME FM_CPU0_PKGID0
J 0
(-4375 4010);
DISPLAY 0.617021 (-4375 4010);
PAINT ORANGE (-4375 4010);
WIRE 16 -1 (-1350 3750)(250 3750);
FORCEPROP 0 LAST SIG_NAME FM_OC0_USB_N
J 0
(-1125 3760);
DISPLAY 0.617021 (-1125 3760);
PAINT ORANGE (-1125 3760);
WIRE 16 -1 (-1350 1700)(250 1700);
FORCEPROP 2 LAST SIG_NAME FM_CPU0_SKTOCC_LVT3_N
J 0
(-1125 1710);
DISPLAY 0.617021 (-1125 1710);
PAINT ORANGE (-1125 1710);
WIRE 16 -1 (-2550 1650)(-4425 1650);
FORCEPROP 0 LAST SIG_NAME FM_GLOBAL_RST_WARN_N
J 0
(-4375 1660);
DISPLAY 0.617021 (-4375 1660);
PAINT ORANGE (-4375 1660);
WIRE 16 -1 (-3225 5000)(-4050 5000);
FORCEPROP 0 LAST SIG_NAME RST_CPU1_LVC3_N
J 0
(-3910 5010);
DISPLAY 0.617021 (-3910 5010);
PAINT ORANGE (-3910 5010);
WIRE 16 -1 (-2550 4050)(-4425 4050);
FORCEPROP 0 LAST SIG_NAME CLK_32K_SUSCLK_PLD
J 0
(-4375 4060);
DISPLAY 0.617021 (-4375 4060);
PAINT ORANGE (-4375 4060);
WIRE 16 -1 (-1350 2850)(25 2850);
FORCEPROP 2 LAST SIG_NAME TP_CPLD1_PB16A_PCLKT2_1
J 0
(-1125 2875);
DISPLAY 0.617021 (-1125 2875);
PAINT ORANGE (-1125 2875);
FORCEPROP 2 LASTPROP $XRERR UNIQUE?
J 0
(55 2850);
DISPLAY 0.638298 (55 2850);
PAINT MONO (55 2850);
DISPLAY INVISIBLE (55 2850);
WIRE 16 -1 (-2550 4550)(-3900 4550);
FORCEPROP 0 LAST SIG_NAME TP_CPLD1_PL1A_L_GPLLT_FB
J 0
(-3895 4560);
DISPLAY 0.617021 (-3895 4560);
PAINT ORANGE (-3895 4560);
FORCEPROP 2 LASTPROP $XRERR UNIQUE?
J 0
(-4140 4550);
DISPLAY 0.638298 (-4140 4550);
PAINT MONO (-4140 4550);
DISPLAY INVISIBLE (-4140 4550);
WIRE 16 -1 (-1350 2050)(250 2050);
FORCEPROP 2 LAST SIG_NAME FM_UARTSW_MSB_N
J 0
(-1125 2060);
DISPLAY 0.617021 (-1125 2060);
PAINT ORANGE (-1125 2060);
WIRE 16 -1 (-2550 3750)(-4425 3750);
FORCEPROP 0 LAST SIG_NAME FM_CPU0_PROC_ID0
J 0
(-4375 3760);
DISPLAY 0.617021 (-4375 3760);
PAINT ORANGE (-4375 3760);
WIRE 16 -1 (-2550 4450)(-4425 4450);
FORCEPROP 0 LAST SIG_NAME RST_PCIE_PCH_PERST_N
J 0
(-4375 4460);
DISPLAY 0.617021 (-4375 4460);
PAINT ORANGE (-4375 4460);
WIRE 16 -1 (-3200 3900)(-2550 3900);
FORCEPROP 0 LAST SIG_NAME FM_PWR_BTN_R2_N
J 0
(-3150 3910);
DISPLAY 0.617021 (-3150 3910);
PAINT ORANGE (-3150 3910);
FORCEPROP 2 LASTPROP $XRERR UNIQUE?
J 0
(-3390 3910);
DISPLAY 0.638298 (-3390 3910);
PAINT MONO (-3390 3910);
DISPLAY INVISIBLE (-3390 3910);
WIRE 16 -1 (-4875 5000)(-4250 5000);
FORCEPROP 0 LAST SIG_NAME RST_CPU1_LVC3_R1_N
J 0
(-4860 5010);
DISPLAY 0.617021 (-4860 5010);
PAINT ORANGE (-4860 5010);
WIRE 16 -1 (-3400 3900)(-4425 3900);
FORCEPROP 0 LAST SIG_NAME FM_PWR_BTN_N
J 0
(-4375 3910);
DISPLAY 0.617021 (-4375 3910);
PAINT ORANGE (-4375 3910);
WIRE 16 -1 (-2550 3950)(-4425 3950);
FORCEPROP 0 LAST SIG_NAME PU_RST_PERST_BIT0
J 0
(-4375 3960);
DISPLAY 0.617021 (-4375 3960);
PAINT ORANGE (-4375 3960);
WIRE 16 -1 (-2550 4250)(-3900 4250);
FORCEPROP 0 LAST SIG_NAME TP_CPLD1_PL2B_L_GPLLC_IN
J 0
(-3895 4260);
DISPLAY 0.617021 (-3895 4260);
PAINT ORANGE (-3895 4260);
FORCEPROP 2 LASTPROP $XRERR UNIQUE?
J 0
(-4140 4250);
DISPLAY 0.638298 (-4140 4250);
PAINT MONO (-4140 4250);
DISPLAY INVISIBLE (-4140 4250);
WIRE 16 -1 (-2550 4200)(-4425 4200);
FORCEPROP 0 LAST SIG_NAME RST_PCIE_CPU_DEV1_N
J 0
(-4375 4210);
DISPLAY 0.617021 (-4375 4210);
PAINT ORANGE (-4375 4210);
WIRE 16 -1 (-2550 4150)(-4425 4150);
WIRE 16 -1 (-2550 3700)(-4425 3700);
FORCEPROP 0 LAST SIG_NAME FM_DEBUG_RST_BTN_N
J 0
(-4375 3710);
DISPLAY 0.617021 (-4375 3710);
PAINT ORANGE (-4375 3710);
WIRE 16 -1 (-2550 3650)(-4425 3650);
FORCEPROP 0 LAST SIG_NAME RST_RSMRST_R_N
J 0
(-4375 3660);
DISPLAY 0.617021 (-4375 3660);
PAINT ORANGE (-4375 3660);
WIRE 16 -1 (-2550 4300)(-4425 4300);
FORCEPROP 0 LAST SIG_NAME FM_CPU_CATERR_DLY_LVT3_N
J 0
(-4375 4310);
DISPLAY 0.617021 (-4375 4310);
PAINT ORANGE (-4375 4310);
WIRE 16 -1 (-2550 4400)(-4425 4400);
FORCEPROP 0 LAST SIG_NAME FM_PCH_PLD_DATA
J 0
(-4385 4410);
DISPLAY 0.617021 (-4385 4410);
PAINT ORANGE (-4385 4410);
WIRE 16 -1 (-2550 4500)(-3900 4500);
FORCEPROP 0 LAST SIG_NAME TP_CPLD1_PL1B_L_GPLLC_FB
J 0
(-3895 4510);
DISPLAY 0.617021 (-3895 4510);
PAINT ORANGE (-3895 4510);
FORCEPROP 2 LASTPROP $XRERR UNIQUE?
J 0
(-4140 4500);
DISPLAY 0.638298 (-4140 4500);
PAINT MONO (-4140 4500);
DISPLAY INVISIBLE (-4140 4500);
WIRE 16 -1 (-4250 5200)(-4875 5200);
FORCEPROP 0 LAST SIG_NAME RST_CPU0_LVC3_R1_N
J 0
(-4860 5210);
DISPLAY 0.617021 (-4860 5210);
PAINT ORANGE (-4860 5210);
WIRE 3 682 (-1900 4750)(-1550 4750);
WIRE 3 682 (-1550 5125)(-1550 4750);
WIRE 3 682 (-1900 4750)(-1900 5125);
WIRE 3 682 (-1900 5125)(-1550 5125);
WIRE 16 -1 (-1800 5200)(-2200 5200);
WIRE 16 -1 (-1800 5200)(-1800 5100);
WIRE 16 -1 (-1450 5200)(-1800 5200);
WIRE 16 -1 (-1350 4550)(250 4550);
FORCEPROP 2 LAST SIG_NAME PWRGD_PVSA_CPU1
J 0
(-1125 4560);
DISPLAY 0.617021 (-1125 4560);
PAINT ORANGE (-1125 4560);
WIRE 16 -1 (-1350 4500)(250 4500);
FORCEPROP 0 LAST SIG_NAME FM_ADR_MODE_SEL
J 0
(-1110 4510);
DISPLAY 0.617021 (-1110 4510);
PAINT ORANGE (-1110 4510);
WIRE 16 -1 (-1350 4450)(250 4450);
FORCEPROP 2 LAST SIG_NAME FM_CPU0_RC_EN
J 0
(-1125 4460);
DISPLAY 0.617021 (-1125 4460);
PAINT ORANGE (-1125 4460);
WIRE 16 -1 (-1350 4350)(25 4350);
FORCEPROP 2 LAST SIG_NAME TP_CPLD1_PB5A_CSSPIN
J 0
(-1125 4360);
DISPLAY 0.617021 (-1125 4360);
PAINT ORANGE (-1125 4360);
FORCEPROP 2 LASTPROP $XRERR UNIQUE?
J 0
(55 4350);
DISPLAY 0.638298 (55 4350);
PAINT MONO (55 4350);
DISPLAY INVISIBLE (55 4350);
WIRE 16 -1 (-1350 4300)(250 4300);
FORCEPROP 2 LAST SIG_NAME PWRGD_PVCCMCP_CPU0
J 0
(-1125 4310);
DISPLAY 0.617021 (-1125 4310);
PAINT ORANGE (-1125 4310);
WIRE 16 -1 (-1350 4150)(250 4150);
FORCEPROP 2 LAST SIG_NAME PWRGD_PVCCIOMCP_CPU1
J 0
(-1125 4160);
DISPLAY 0.617021 (-1125 4160);
PAINT ORANGE (-1125 4160);
WIRE 16 -1 (-1350 4050)(250 4050);
FORCEPROP 2 LAST SIG_NAME FM_DIS_ADR_DLY
J 0
(-1125 4060);
DISPLAY 0.617021 (-1125 4060);
PAINT ORANGE (-1125 4060);
WIRE 16 -1 (-1350 4000)(250 4000);
FORCEPROP 2 LAST SIG_NAME FM_BMC_CPLD_MP_RST_N
J 0
(-1125 4010);
DISPLAY 0.617021 (-1125 4010);
PAINT ORANGE (-1125 4010);
WIRE 16 -1 (-1350 3800)(250 3800);
FORCEPROP 2 LAST SIG_NAME PWRGD_PVCCIOMCP_CPU0
J 0
(-1125 3810);
DISPLAY 0.617021 (-1125 3810);
PAINT ORANGE (-1125 3810);
WIRE 16 -1 (-1350 3650)(250 3650);
FORCEPROP 2 LAST SIG_NAME PWRGD_PVTT_CPU1
J 0
(-1125 3660);
DISPLAY 0.617021 (-1125 3660);
PAINT ORANGE (-1125 3660);
WIRE 16 -1 (-1350 3600)(250 3600);
FORCEPROP 2 LAST SIG_NAME FM_PVCCIOMCP_CPU1_EN
J 0
(-1125 3610);
DISPLAY 0.617021 (-1125 3610);
PAINT ORANGE (-1125 3610);
WIRE 16 -1 (-1350 3550)(250 3550);
FORCEPROP 2 LAST SIG_NAME FM_PVCCIO_CPU0_EN
J 0
(-1125 3560);
DISPLAY 0.617021 (-1125 3560);
PAINT ORANGE (-1125 3560);
WIRE 16 -1 (-1350 3500)(250 3500);
FORCEPROP 2 LAST SIG_NAME PWRGD_PVPP_ABC
J 0
(-1125 3510);
DISPLAY 0.617021 (-1125 3510);
PAINT ORANGE (-1125 3510);
WIRE 16 -1 (-1350 3400)(250 3400);
FORCEPROP 2 LAST SIG_NAME FM_PVCCIO_CPU1_EN
J 0
(-1125 3410);
DISPLAY 0.617021 (-1125 3410);
PAINT ORANGE (-1125 3410);
WIRE 16 -1 (-1350 3350)(250 3350);
FORCEPROP 2 LAST SIG_NAME FM_CPLD_USB_P0_EN_N
J 0
(-1125 3360);
DISPLAY 0.617021 (-1125 3360);
PAINT ORANGE (-1125 3360);
WIRE 16 -1 (-2550 3800)(-4425 3800);
FORCEPROP 0 LAST SIG_NAME FM_CPU0_PROC_ID1
J 0
(-4375 3810);
DISPLAY 0.617021 (-4375 3810);
PAINT ORANGE (-4375 3810);
WIRE 16 -1 (-2550 3500)(-4425 3500);
FORCEPROP 0 LAST SIG_NAME FM_CPU0_PKGID1
J 0
(-4375 3510);
DISPLAY 0.617021 (-4375 3510);
PAINT ORANGE (-4375 3510);
WIRE 16 -1 (-2550 3450)(-4425 3450);
FORCEPROP 0 LAST SIG_NAME FM_CPU0_FIVR_FAULT_LVT3_N
J 0
(-4375 3460);
DISPLAY 0.617021 (-4375 3460);
PAINT ORANGE (-4375 3460);
WIRE 16 -1 (-2550 3400)(-4425 3400);
FORCEPROP 0 LAST SIG_NAME PWRGD_P3V3
J 0
(-4375 3410);
DISPLAY 0.617021 (-4375 3410);
PAINT ORANGE (-4375 3410);
WIRE 16 -1 (-2550 3300)(-4425 3300);
FORCEPROP 0 LAST SIG_NAME FM_SLPS3_N
J 0
(-4375 3310);
DISPLAY 0.617021 (-4375 3310);
PAINT ORANGE (-4375 3310);
WIRE 16 -1 (-2550 3250)(-4425 3250);
FORCEPROP 0 LAST SIG_NAME FM_PVCCMCP_CPU0_EN
J 0
(-4359 3256);
DISPLAY 0.617021 (-4359 3256);
PAINT ORANGE (-4359 3256);
WIRE 16 -1 (-2550 3200)(-4425 3200);
FORCEPROP 0 LAST SIG_NAME FM_MP_PS_FAIL_N
J 0
(-4375 3210);
DISPLAY 0.617021 (-4375 3210);
PAINT ORANGE (-4375 3210);
WIRE 16 -1 (-2550 3150)(-4425 3150);
FORCEPROP 0 LAST SIG_NAME PWRGD_P5V
J 0
(-4375 3160);
DISPLAY 0.617021 (-4375 3160);
PAINT ORANGE (-4375 3160);
WIRE 16 -1 (-2550 3550)(-4425 3550);
FORCEPROP 0 LAST SIG_NAME FM_CPU0_PKGID2
J 0
(-4375 3560);
DISPLAY 0.617021 (-4375 3560);
PAINT ORANGE (-4375 3560);
WIRE 16 -1 (-1250 5200)(-550 5200);
WIRE 16 -1 (-1350 4600)(250 4600);
FORCEPROP 2 LAST SIG_NAME FM_CPU1_RC_EN
J 0
(-1125 4610);
DISPLAY 0.617021 (-1125 4610);
PAINT ORANGE (-1125 4610);
WIRE 16 -1 (-1350 4100)(250 4100);
FORCEPROP 2 LAST SIG_NAME RST_PCIE_M2_DEV_N
J 0
(-1125 4110);
DISPLAY 0.617021 (-1125 4110);
PAINT ORANGE (-1125 4110);
WIRE 16 -1 (-1350 3300)(250 3300);
FORCEPROP 0 LAST SIG_NAME PWRGD_PVPP_DEF
J 0
(-1125 3310);
DISPLAY 0.617021 (-1125 3310);
PAINT ORANGE (-1125 3310);
WIRE 16 -1 (-1350 3250)(250 3250);
FORCEPROP 2 LAST SIG_NAME PWRGD_PVCCIO_CPU0
J 0
(-1125 3260);
DISPLAY 0.617021 (-1125 3260);
PAINT ORANGE (-1125 3260);
WIRE 16 -1 (-1350 3150)(250 3150);
FORCEPROP 2 LAST SIG_NAME PWRGD_PVNN_P1V05_PCH
J 0
(-1125 3160);
DISPLAY 0.617021 (-1125 3160);
PAINT ORANGE (-1125 3160);
WIRE 16 -1 (-1350 3100)(250 3100);
FORCEPROP 2 LAST SIG_NAME FM_CPLD_DBG_PWR_EN_N
J 0
(-1125 3110);
DISPLAY 0.617021 (-1125 3110);
PAINT ORANGE (-1125 3110);
WIRE 16 -1 (-1350 3050)(250 3050);
FORCEPROP 2 LAST SIG_NAME FM_156M_CPU1_BRD_OSC_EN
J 0
(-1125 3060);
DISPLAY 0.617021 (-1125 3060);
PAINT ORANGE (-1125 3060);
WIRE 16 -1 (-1350 3000)(250 3000);
FORCEPROP 0 LAST SIG_NAME FM_IE_DISABLE_N
J 0
(-1125 3010);
DISPLAY 0.617021 (-1125 3010);
PAINT ORANGE (-1125 3010);
WIRE 16 -1 (-1350 3850)(25 3850);
FORCEPROP 2 LAST SIG_NAME TP_CPLD1_PB8B_SO_SPISO
J 0
(-1125 3860);
DISPLAY 0.617021 (-1125 3860);
PAINT ORANGE (-1125 3860);
FORCEPROP 2 LASTPROP $XRERR UNIQUE?
J 0
(55 3850);
DISPLAY 0.638298 (55 3850);
PAINT MONO (55 3850);
DISPLAY INVISIBLE (55 3850);
WIRE 16 -1 (-1350 3900)(25 3900);
FORCEPROP 2 LAST SIG_NAME TP_CPLD1_PB8A_MCLK_CCLK
J 0
(-1125 3910);
DISPLAY 0.617021 (-1125 3910);
PAINT ORANGE (-1125 3910);
FORCEPROP 2 LASTPROP $XRERR UNIQUE?
J 0
(55 3900);
DISPLAY 0.638298 (55 3900);
PAINT MONO (55 3900);
DISPLAY INVISIBLE (55 3900);
WIRE 16 -1 (-4050 5200)(-3225 5200);
FORCEPROP 0 LAST SIG_NAME RST_CPU0_LVC3_N
J 0
(-3910 5210);
DISPLAY 0.617021 (-3910 5210);
PAINT ORANGE (-3910 5210);
WIRE 16 -1 (-1350 2600)(250 2600);
FORCEPROP 2 LAST SIG_NAME FM_UARTSW_LSB_N
J 0
(-1125 2610);
DISPLAY 0.617021 (-1125 2610);
PAINT ORANGE (-1125 2610);
WIRE 16 -1 (-1350 2550)(250 2550);
FORCEPROP 2 LAST SIG_NAME FM_156M_CPU0_BRD_OSC_EN
J 0
(-1125 2560);
DISPLAY 0.617021 (-1125 2560);
PAINT ORANGE (-1125 2560);
WIRE 16 -1 (-1350 1400)(25 1400);
FORCEPROP 2 LAST SIG_NAME TP_CPLD1_PB25B_SI_SISPI
J 0
(-1125 1410);
DISPLAY 0.617021 (-1125 1410);
PAINT ORANGE (-1125 1410);
FORCEPROP 2 LASTPROP $XRERR UNIQUE?
J 0
(55 1400);
DISPLAY 0.638298 (55 1400);
PAINT MONO (55 1400);
DISPLAY INVISIBLE (55 1400);
WIRE 16 -1 (-1350 2700)(250 2700);
FORCEPROP 2 LAST SIG_NAME FM_CPLD_BMC_PWRDN_N
J 0
(-1125 2710);
DISPLAY 0.617021 (-1125 2710);
PAINT ORANGE (-1125 2710);
WIRE 16 -1 (250 1850)(-1350 1850);
FORCEPROP 2 LAST SIG_NAME FM_DB1200ZL_BCLKS_EN_N
J 0
(-1125 1860);
DISPLAY 0.617021 (-1125 1860);
PAINT ORANGE (-1125 1860);
WIRE 16 -1 (-1350 1800)(250 1800);
FORCEPROP 2 LAST SIG_NAME FM_CPU1_SKTOCC_LVT3_N
J 0
(-1125 1810);
DISPLAY 0.617021 (-1125 1810);
PAINT ORANGE (-1125 1810);
WIRE 16 -1 (-1350 1750)(250 1750);
FORCEPROP 2 LAST SIG_NAME FM_CPU0_VRM_OSC_EN
J 0
(-1125 1760);
DISPLAY 0.617021 (-1125 1760);
PAINT ORANGE (-1125 1760);
WIRE 16 -1 (-1350 1450)(250 1450);
FORCEPROP 2 LAST SIG_NAME FM_CPU1_PKGID0
J 0
(-1125 1460);
DISPLAY 0.617021 (-1125 1460);
PAINT ORANGE (-1125 1460);
WIRE 16 -1 (-1350 1350)(250 1350);
FORCEPROP 2 LAST SIG_NAME PWRGD_DRAMPWRGD
J 0
(-1125 1360);
DISPLAY 0.617021 (-1125 1360);
PAINT ORANGE (-1125 1360);
WIRE 16 -1 (-1350 1300)(250 1300);
FORCEPROP 2 LAST SIG_NAME FM_CPU_CATERR_LVT3_N
J 0
(-1125 1310);
DISPLAY 0.617021 (-1125 1310);
PAINT ORANGE (-1125 1310);
WIRE 16 -1 (-1350 2200)(250 2200);
FORCEPROP 2 LAST SIG_NAME XDP_PWRGD_RST_N
J 0
(-1125 2210);
DISPLAY 0.617021 (-1125 2210);
PAINT ORANGE (-1125 2210);
WIRE 16 -1 (-1350 2000)(250 2000);
FORCEPROP 2 LAST SIG_NAME PWRGD_CPU1_LVC3
J 0
(-1125 2010);
DISPLAY 0.617021 (-1125 2010);
PAINT ORANGE (-1125 2010);
WIRE 16 -1 (-1350 1950)(250 1950);
FORCEPROP 2 LAST SIG_NAME XDP_SYSPWROK
J 0
(-1125 1960);
DISPLAY 0.617021 (-1125 1960);
PAINT ORANGE (-1125 1960);
WIRE 16 -1 (-1350 2350)(250 2350);
FORCEPROP 2 LAST SIG_NAME RST_CD_CPU1_POR_N
J 0
(-1125 2360);
DISPLAY 0.617021 (-1125 2360);
PAINT ORANGE (-1125 2360);
WIRE 16 -1 (-1350 2450)(250 2450);
FORCEPROP 0 LAST SIG_NAME FM_SOL_UART_CH_SEL
J 0
(-1125 2460);
DISPLAY 0.617021 (-1125 2460);
PAINT ORANGE (-1125 2460);
WIRE 16 -1 (-1350 2800)(25 2800);
FORCEPROP 2 LAST SIG_NAME TP_CPLD1_PB16B_PCLKC2_1
J 0
(-1125 2810);
DISPLAY 0.617021 (-1125 2810);
PAINT ORANGE (-1125 2810);
FORCEPROP 2 LASTPROP $XRERR UNIQUE?
J 0
(55 2800);
DISPLAY 0.638298 (55 2800);
PAINT MONO (55 2800);
DISPLAY INVISIBLE (55 2800);
WIRE 16 -1 (-1350 2750)(250 2750);
FORCEPROP 2 LAST SIG_NAME FM_PVCCMCP_CPU1_EN
J 0
(-1125 2760);
DISPLAY 0.617021 (-1125 2760);
PAINT ORANGE (-1125 2760);
WIRE 16 -1 (-1350 2500)(250 2500);
FORCEPROP 2 LAST SIG_NAME FM_CPLD_UART_CH_LOCK_N
J 0
(-1125 2510);
DISPLAY 0.617021 (-1125 2510);
PAINT ORANGE (-1125 2510);
WIRE 16 -1 (-1350 2300)(250 2300);
FORCEPROP 2 LAST SIG_NAME RST_CPU0_LVC3_R1_N
J 0
(-1125 2310);
DISPLAY 0.617021 (-1125 2310);
PAINT ORANGE (-1125 2310);
WIRE 16 -1 (-1350 2250)(250 2250);
FORCEPROP 2 LAST SIG_NAME RST_CPU1_LVC3_R1_N
J 0
(-1125 2260);
DISPLAY 0.617021 (-1125 2260);
PAINT ORANGE (-1125 2260);
WIRE 16 -1 (-1350 2100)(250 2100);
FORCEPROP 2 LAST SIG_NAME FM_CPU1_PKGID2
J 0
(-1125 2110);
DISPLAY 0.617021 (-1125 2110);
PAINT ORANGE (-1125 2110);
WIRE 2 -1 (1350 3350)(700 3350);
WIRE 2 -1 (1350 3750)(700 3750);
WIRE 2 -1 (1350 3800)(1350 3750);
WIRE 2 -1 (1350 3750)(1350 3350);
WIRE 16 -1 (-2550 3050)(-4425 3050);
FORCEPROP 0 LAST SIG_NAME RST_PCIE_CPU_DEV2_N
J 0
(-4375 3060);
DISPLAY 0.617021 (-4375 3060);
PAINT ORANGE (-4375 3060);
WIRE 16 -1 (-2550 3000)(-4425 3000);
FORCEPROP 0 LAST SIG_NAME RST_PCIE_CPU_DEV3_N
J 0
(-4375 3010);
DISPLAY 0.617021 (-4375 3010);
PAINT ORANGE (-4375 3010);
WIRE 16 -1 (-2550 2450)(-4425 2450);
FORCEPROP 0 LAST SIG_NAME UART_BMC_RXD5
J 0
(-4370 2460);
DISPLAY 0.617021 (-4370 2460);
PAINT ORANGE (-4370 2460);
WIRE 16 -1 (-1350 1550)(250 1550);
FORCEPROP 2 LAST SIG_NAME FM_CPU_MSMI_LVT3_N
J 0
(-1125 1560);
DISPLAY 0.617021 (-1125 1560);
PAINT ORANGE (-1125 1560);
WIRE 16 -1 (-1350 1600)(250 1600);
FORCEPROP 2 LAST SIG_NAME FM_CPU1_PKGID1
J 0
(-1125 1610);
DISPLAY 0.617021 (-1125 1610);
PAINT ORANGE (-1125 1610);
WIRE 16 -1 (-2550 1400)(-4425 1400);
FORCEPROP 0 LAST SIG_NAME FM_UART_ALERT_N
J 0
(-4375 1410);
DISPLAY 0.617021 (-4375 1410);
PAINT ORANGE (-4375 1410);
WIRE 16 -1 (-2550 1450)(-4425 1450);
FORCEPROP 0 LAST SIG_NAME FM_BMC_CPLD_GPO
J 0
(-4375 1460);
DISPLAY 0.617021 (-4375 1460);
PAINT ORANGE (-4375 1460);
WIRE 16 -1 (-2550 2500)(-4425 2500);
FORCEPROP 0 LAST SIG_NAME SP1_BMC_HOST_UART_TX
J 0
(-4375 2510);
DISPLAY 0.617021 (-4375 2510);
PAINT ORANGE (-4375 2510);
WIRE 16 -1 (-2550 2400)(-4425 2400);
FORCEPROP 0 LAST SIG_NAME UART_BMC_TXD5
J 0
(-4370 2410);
DISPLAY 0.617021 (-4370 2410);
PAINT ORANGE (-4370 2410);
WIRE 16 -1 (-2550 2550)(-4425 2550);
FORCEPROP 0 LAST SIG_NAME SP1_BMC_HOST_UART_RX
J 0
(-4375 2560);
DISPLAY 0.617021 (-4375 2560);
PAINT ORANGE (-4375 2560);
WIRE 3 682 (-3400 2700)(-3350 2700);
WIRE 3 682 (-3350 2700)(-2700 2700);
WIRE 3 682 (-3350 2700)(-3350 2650);
WIRE 3 682 (-3350 2650)(-2700 2650);
WIRE 16 -1 (-2550 2750)(-4425 2750);
FORCEPROP 0 LAST SIG_NAME FM_PVCCIOMCP_CPU0_EN
J 0
(-4374 2766);
DISPLAY 0.617021 (-4374 2766);
PAINT ORANGE (-4374 2766);
WIRE 16 -1 (-2550 2800)(-4425 2800);
FORCEPROP 0 LAST SIG_NAME SGPIO_BMC_DOUT
J 0
(-4375 2810);
DISPLAY 0.617021 (-4375 2810);
PAINT ORANGE (-4375 2810);
WIRE 16 -1 (-2550 2900)(-3900 2900);
FORCEPROP 0 LAST SIG_NAME TP_CPLD1_PL7D_PCLKT4_0
J 0
(-3895 2910);
DISPLAY 0.617021 (-3895 2910);
PAINT ORANGE (-3895 2910);
FORCEPROP 2 LASTPROP $XRERR UNIQUE?
J 0
(-4140 2900);
DISPLAY 0.638298 (-4140 2900);
PAINT MONO (-4140 2900);
DISPLAY INVISIBLE (-4140 2900);
WIRE 16 -1 (-2550 2950)(-4425 2950);
FORCEPROP 0 LAST SIG_NAME SGPIO_BMC_CLK
J 0
(-4375 2960);
DISPLAY 0.617021 (-4375 2960);
PAINT ORANGE (-4375 2960);
WIRE 16 -1 (-2550 2300)(-4425 2300);
FORCEPROP 0 LAST SIG_NAME PWRGD_PVSA_CPU0
J 0
(-4375 2310);
DISPLAY 0.617021 (-4375 2310);
PAINT ORANGE (-4375 2310);
WIRE 16 -1 (-2550 2250)(-3900 2250);
FORCEPROP 0 LAST SIG_NAME TP_CPLD1_PL11A
J 0
(-3850 2260);
DISPLAY 0.617021 (-3850 2260);
PAINT ORANGE (-3850 2260);
FORCEPROP 2 LASTPROP $XRERR UNIQUE?
J 0
(-4140 2250);
DISPLAY 0.638298 (-4140 2250);
PAINT MONO (-4140 2250);
DISPLAY INVISIBLE (-4140 2250);
WIRE 16 -1 (-2550 2200)(-4425 2200);
FORCEPROP 0 LAST SIG_NAME SGPIO_BMC_LD_N
J 0
(-4370 2210);
DISPLAY 0.617021 (-4370 2210);
PAINT ORANGE (-4370 2210);
WIRE 16 -1 (-2550 2150)(-4425 2150);
FORCEPROP 0 LAST SIG_NAME PWRGD_CPU0_LVC3
J 0
(-4375 2160);
DISPLAY 0.617021 (-4375 2160);
PAINT ORANGE (-4375 2160);
WIRE 16 -1 (-2550 2050)(-4425 2050);
FORCEPROP 0 LAST SIG_NAME CLK_25M_CPLD
J 0
(-4375 2060);
DISPLAY 0.617021 (-4375 2060);
PAINT ORANGE (-4375 2060);
WIRE 16 -1 (-2550 2000)(-4425 2000);
FORCEPROP 0 LAST SIG_NAME RST_RSMRST_DLY
J 0
(-4375 2010);
DISPLAY 0.617021 (-4375 2010);
PAINT ORANGE (-4375 2010);
WIRE 16 -1 (-2550 1950)(-4425 1950);
FORCEPROP 0 LAST SIG_NAME PWRGD_PVCCIN_CPU0
J 0
(-4375 1960);
DISPLAY 0.617021 (-4375 1960);
PAINT ORANGE (-4375 1960);
WIRE 16 -1 (-2550 1900)(-4425 1900);
FORCEPROP 0 LAST SIG_NAME PWRGD_PVCCMCP_CPU1
J 0
(-4375 1904);
DISPLAY 0.617021 (-4375 1904);
PAINT ORANGE (-4375 1904);
WIRE 16 -1 (-2550 1800)(-4425 1800);
FORCEPROP 0 LAST SIG_NAME RST_PCIE_RISER1_PERST_N
J 0
(-4375 1810);
DISPLAY 0.617021 (-4375 1810);
PAINT ORANGE (-4375 1810);
WIRE 16 -1 (-2550 1750)(-4425 1750);
FORCEPROP 0 LAST SIG_NAME PWRGD_PVCCIN_CPU1
J 0
(-4375 1760);
DISPLAY 0.617021 (-4375 1760);
PAINT ORANGE (-4375 1760);
WIRE 16 -1 (-2550 1700)(-4425 1700);
FORCEPROP 0 LAST SIG_NAME PWRGD_PVPP_KLM
J 0
(-4375 1710);
DISPLAY 0.617021 (-4375 1710);
PAINT ORANGE (-4375 1710);
WIRE 16 -1 (-2550 1550)(-4425 1550);
FORCEPROP 0 LAST SIG_NAME PWRGD_PVPP_GHJ
J 0
(-4375 1560);
DISPLAY 0.617021 (-4375 1560);
PAINT ORANGE (-4375 1560);
WIRE 16 -1 (-2550 1500)(-4425 1500);
FORCEPROP 0 LAST SIG_NAME RST_CD_CPU0_POR_N
J 0
(-4375 1510);
DISPLAY 0.617021 (-4375 1510);
PAINT ORANGE (-4375 1510);
DOT 1 (-1800 5200);
DOT 1 (-3350 2700);
DOT 1 (1350 3750);
FORCENOTE
BOM_COST=CPLD
(-5225 725) 0;
DISPLAY LEFT (-5225 725);
DISPLAY 1.021277 (-5225 725);
PAINT PURPLE (-5225 725);
FORCENOTE
ROOM=CPLD
(-5225 775) 0;
DISPLAY LEFT (-5225 775);
DISPLAY 1.021277 (-5225 775);
PAINT PURPLE (-5225 775);
FORCENOTE
TP FAB1 NC (NO USE IE) 0118
(-4725 2650) 0;
DISPLAY LEFT (-4725 2650);
DISPLAY 1.021277 (-4725 2650);
PAINT RED (-4725 2650);
FORCENOTE
TP FAB1 ADD RES 0217
(-1550 4800) 0;
DISPLAY LEFT (-1550 4800);
DISPLAY 1.021277 (-1550 4800);
PAINT RED (-1550 4800);
FORCENOTE
TP FAB1 ADD RES 0226
(-3300 3825) 0;
DISPLAY LEFT (-3300 3825);
DISPLAY 1.021277 (-3300 3825);
PAINT RED (-3300 3825);
FORCENOTE
TP FAB1 CONNECT TO USB3.0 OC IC 1221
(725 3825) 0;
DISPLAY LEFT (725 3825);
DISPLAY 1.021277 (725 3825);
PAINT RED (725 3825);
QUIT
